G04 ================== begin FILE IDENTIFICATION RECORD ==================*
G04 Layout Name:  DA0T6MTH8C0_t6m_tray_bp_c_brd_103112_274.brd*
G04 Film Name:    in2*
G04 File Format:  Gerber RS274X*
G04 File Origin:  Cadence Allegro 16.3-S048*
G04 Origin Date:  Tue Nov 26 11:26:41 2013*
G04 *
G04 Layer:  DRAWING FORMAT/TITLE_BLOCK*
G04 Layer:  VIA CLASS/IN2*
G04 Layer:  PIN/IN2*
G04 Layer:  MANUFACTURING/PHOTOPLOT_OUTLINE*
G04 Layer:  ETCH/IN2*
G04 Layer:  DRAWING FORMAT/TITLE_DATA_IN2*
G04 *
G04 Offset:    (0.00 0.00)*
G04 Mirror:    No*
G04 Mode:      Positive*
G04 Rotation:  0*
G04 FullContactRelief:  No*
G04 UndefLineWidth:     6.00*
G04 ================== end FILE IDENTIFICATION RECORD ====================*
%FSLAX25Y25*MOIN*%
%IR0*IPPOS*OFA0.00000B0.00000*MIA0B0*SFA1.00000B1.00000*%
%ADD12C,.02*%
%ADD13C,.04*%
%ADD18C,.051*%
%ADD17C,.061*%
%ADD20C,.036*%
%ADD11C,.054*%
%ADD10C,.063*%
%ADD16C,.046*%
%ADD22C,.092*%
%ADD19C,.12*%
%ADD14C,.213*%
%ADD15C,.228*%
%ADD21C,.139*%
%ADD23C,.025*%
%ADD24C,.018*%
%ADD25C,.006*%
%ADD26C,.0072*%
%ADD27C,.03004*%
%ADD28C,.05004*%
%ADD32C,.07304*%
%ADD31C,.06404*%
%ADD29C,.05604*%
%ADD30C,.07604*%
%ADD36C,.07606*%
%ADD33C,.1601*%
%ADD37C,.11704*%
%ADD34C,.16024*%
%ADD35C,.11706*%
G75*
%LPD*%
G75*
G36*
G01X55645Y168967D02*
G03X55273Y170901I-2445J533D01*
G02X55334Y171534I415J279D01*
G01X56500Y172700D01*
X59196D01*
G02X60054Y171186I0J-1000D01*
G03X64346I2146J-1286D01*
G02X65204Y172700I858J514D01*
G01X67338D01*
G02X68213Y171215I0J-1000D01*
G03X72587I2187J-1215D01*
G02X73462Y172700I875J485D01*
G01X75196D01*
G02X76054Y171186I0J-1000D01*
G03X80032Y168196I2146J-1286D01*
G02X81545Y168138I731J-682D01*
G03X85554Y171129I1955J1562D01*
G02X86375Y172700I821J571D01*
G01X87475D01*
G02X88253Y171072I0J-1000D01*
G03X88382Y167781I1947J-1572D01*
G02X88353Y166377I-726J-687D01*
G03X90770Y165916I1047J-1077D01*
G02X91259Y167233I912J411D01*
G03X92147Y171072I-1059J2267D01*
G02X92925Y172700I778J628D01*
G01X94175D01*
G02X94953Y171072I0J-1000D01*
G03X98847I1947J-1572D01*
G02X99625Y172700I778J628D01*
G01X103290D01*
G02X104207Y171300I0J-1000D01*
G03X105012Y168289I2293J-1000D01*
G02X104970Y166652I-595J-804D01*
G03X106948Y166369I830J-1252D01*
G02X107366Y167953I764J646D01*
G03X108793Y171300I-866J2347D01*
G02X109710Y172700I917J400D01*
G01X112136D01*
G02X113039Y171272I-1J-1000D01*
G03X117561I2261J-1072D01*
G02X118464Y172700I904J428D01*
G01X189300D01*
X202350Y159650D01*
X224650D01*
X231900Y166900D01*
Y190200D01*
X239700Y198000D01*
X303277D01*
G02X304015Y196325I0J-1000D01*
G03X304716Y176977I10198J-9317D01*
G02X305320Y175572I-1330J-1404D01*
G01Y163386D01*
G03X323106I8893J0D01*
G01X323105Y175572D01*
G02X323710Y176977I1935J0D01*
G03X324411Y196325I-9497J10031D01*
G02X325149Y198000I738J675D01*
G01X368100D01*
X378000Y188100D01*
X444000D01*
X453700Y197800D01*
X518100D01*
X529300Y186600D01*
X594300D01*
X604300Y196600D01*
X623200D01*
X628900Y190900D01*
X806000D01*
X813200Y198100D01*
X815180D01*
G02X815912Y196419I0J-1000D01*
G03X816527Y176977I10112J-9411D01*
G02X816903Y176485I-1329J-1406D01*
G02X817132Y175572I-1706J-913D01*
G01Y171186D01*
X817131Y166800D01*
Y163386D01*
G03X826024Y154493I8893J0D01*
G03X834916Y163386I0J8892D01*
G01Y175572D01*
G02X835145Y176485I1935J0D01*
G02X835521Y176977I1705J-914D01*
G03X836136Y196419I-9497J10031D01*
G02X836868Y198100I732J681D01*
G01X1173448D01*
G02X1174180Y196419I0J-1000D01*
G03X1174795Y176977I10112J-9411D01*
G02X1175171Y176485I-1329J-1406D01*
G02X1175400Y175572I-1706J-913D01*
G01Y163386D01*
G03X1193184I8892J0D01*
G01Y169479D01*
X1193185Y175572D01*
G02X1193789Y176977I1934J1D01*
G03X1194404Y196419I-9497J10031D01*
G02X1195136Y198100I732J681D01*
G01X1233600D01*
X1243900Y187800D01*
X1314500D01*
X1325400Y198700D01*
X1388000D01*
X1398100Y188600D01*
X1465300D01*
X1475100Y198400D01*
X1492900D01*
X1500400Y190900D01*
X1672600D01*
X1675400Y188100D01*
Y169000D01*
X1667000Y160600D01*
Y104100D01*
X1665400Y102500D01*
X1653400D01*
X1646900Y109000D01*
Y126446D01*
G02X1647851Y127445I1000J0D01*
G03X1644370Y135784I-233J4799D01*
G02X1642987Y135813I-676J737D01*
G01X1641000Y137800D01*
X1525600D01*
X1524791Y136991D01*
X1524639Y136962D01*
G03X1520813Y133136I892J-4718D01*
G01X1520784Y132984D01*
X1498100Y110300D01*
X1486188D01*
X1485847Y110438D01*
X1485784Y110492D01*
G03X1484245Y110753I-984J-1135D01*
G01X1484156Y110718D01*
X1461493D01*
X1461075Y110300D01*
X1452600D01*
X1438700Y96400D01*
X1412515D01*
G02X1412162Y96547I1J500D01*
G01X1409247Y99462D01*
X1400638D01*
X1384500Y115600D01*
Y152600D01*
X1378300Y158800D01*
X1343900D01*
X1326600Y141500D01*
X1319500D01*
X1305282Y127282D01*
X1268444D01*
X1252904Y142822D01*
X1219906D01*
G02X1218906Y143851I0J1000D01*
G03X1215904I-1501J44D01*
G02X1214904Y142822I-1000J-29D01*
G01X1213458D01*
G02X1212555Y144253I-1J1000D01*
G03X1209845I-1355J647D01*
G02X1208942Y142822I-902J-431D01*
G01X813244D01*
X800544Y155522D01*
X800400Y155665D01*
X799035D01*
X799000Y155700D01*
X535600D01*
X520300Y171000D01*
X516570D01*
G02X515714Y172516I0J1000D01*
G03X502004I-6855J4134D01*
G02X501148Y171000I-856J-516D01*
G01X471578D01*
G02X470722Y172516I0J1000D01*
G03X456996I-6863J4134D01*
G02X456140Y171000I-856J-516D01*
G01X445800D01*
X430662Y155862D01*
X340542D01*
X318442Y133762D01*
X120341D01*
X120253Y133797D01*
G03X118778Y133586I-553J-1397D01*
G02X117457Y133668I-614J789D01*
G01X115716Y135409D01*
X115678Y135497D01*
G03X113345Y136059I-1378J-597D01*
G02X112002Y136124I-636J772D01*
G01X110316Y137809D01*
X110278Y137897D01*
G03X108303Y135922I-1378J-597D01*
G01X108391Y135884D01*
X111326Y132949D01*
G02X110971Y131306I-707J-707D01*
G03X110903Y128522I529J-1406D01*
G01X110991Y128484D01*
X116700Y122775D01*
Y122700D01*
X116775D01*
X116989Y122485D01*
G02X116635Y121632I-354J-353D01*
G01X116041D01*
X115953Y121667D01*
G03X114390Y121382I-553J-1397D01*
G02X113011Y121415I-672J740D01*
G01X108806Y125619D01*
X108768Y125707D01*
G03X106793Y123732I-1378J-597D01*
G01X106881Y123694D01*
X111928Y118646D01*
G02X111575Y117792I-353J-354D01*
G01X110704D01*
X100516Y127979D01*
X100478Y128067D01*
G03X98503Y126092I-1378J-597D01*
G01X98591Y126054D01*
X109576Y115068D01*
X126137D01*
G02X127122Y114245I1J-1000D01*
G03X127142Y114153I1476J273D01*
G01Y114151D01*
X127156Y114092D01*
Y114032D01*
G02X126656Y113532I-500J0D01*
G01X106664D01*
X104006Y116189D01*
X103968Y116277D01*
G03X101993Y114302I-1378J-597D01*
G01X102081Y114264D01*
X105536Y110808D01*
X130015D01*
G02X131008Y109925I0J-1000D01*
G03X133053Y108703I1492J175D01*
G01X133141Y108738D01*
X327864D01*
X335679Y116554D01*
G02X336032Y116700I353J-354D01*
G01X347100D01*
X348400Y115400D01*
Y107300D01*
X351750Y103950D01*
Y94950D01*
X375400Y71300D01*
Y10500D01*
X370900Y6000D01*
X37900D01*
X35400Y8500D01*
Y25800D01*
X20900Y40300D01*
X15000D01*
X8600Y46700D01*
Y75856D01*
G02X9099Y76356I500J0D01*
G03Y83960I-11J3802D01*
G02X8600Y84460I1J500D01*
G01Y87656D01*
G02X9099Y88156I500J0D01*
G03Y95760I-11J3802D01*
G02X8600Y96260I1J500D01*
G01Y108517D01*
G02X10420Y109089I1000J0D01*
G03X26608Y114173I7296J5084D01*
G01Y126359D01*
G02X27213Y127764I1935J0D01*
G03X16245Y151530I-9497J10031D01*
G02X15431Y153231I-107J994D01*
G01X25700Y163500D01*
X47300D01*
X51148Y167348D01*
G02X51648Y167473I354J-353D01*
G01X51796Y167428D01*
X51854Y167391D01*
G03X53613Y167032I1347J2109D01*
G02X54755Y165833I165J-986D01*
G03X56787Y167768I2445J-533D01*
G02X55645Y168967I-165J986D01*
G37*
G36*
G01X990594Y129099D02*
G02X991511Y130498I917J399D01*
G01X1015089D01*
G02X1016006Y129099I0J-1000D01*
G03X1020594I2294J-999D01*
G02X1021511Y130498I917J399D01*
G01X1045089D01*
G02X1046006Y129099I0J-1000D01*
G03X1050594I2294J-999D01*
G02X1051511Y130498I917J399D01*
G01X1075089D01*
G02X1076006Y129099I0J-1000D01*
G03X1080594I2294J-999D01*
G02X1081511Y130498I917J399D01*
G01X1105089D01*
G02X1106006Y129099I0J-1000D01*
G03X1110594I2294J-999D01*
G02X1111511Y130498I917J399D01*
G01X1206300D01*
G02X1206800Y129998I0J-500D01*
G01Y106400D01*
X1220600Y92600D01*
X1238200D01*
X1245950Y84850D01*
Y13050D01*
X1239900Y7000D01*
X806700D01*
X800400Y13300D01*
Y87100D01*
X785000Y102500D01*
Y132500D01*
X787938Y135438D01*
X801630D01*
G02X801983Y135292I0J-500D01*
G01X806776Y130498D01*
X835089D01*
G02X836006Y129099I0J-1000D01*
G03X840594I2294J-999D01*
G02X841511Y130498I917J399D01*
G01X865089D01*
G02X866006Y129099I0J-1000D01*
G03X870594I2294J-999D01*
G02X871511Y130498I917J399D01*
G01X895089D01*
G02X896006Y129099I0J-1000D01*
G03X900594I2294J-999D01*
G02X901511Y130498I917J399D01*
G01X925089D01*
G02X926006Y129099I0J-1000D01*
G03X930594I2294J-999D01*
G02X931511Y130498I917J399D01*
G01X955089D01*
G02X956006Y129099I0J-1000D01*
G03X960594I2294J-999D01*
G02X961511Y130498I917J399D01*
G01X985089D01*
G02X986006Y129099I0J-1000D01*
G03X990594I2294J-999D01*
G37*
%LPC*%
G75*
G36*
G01X125367Y81132D02*
G02X124068Y79833I191J-1490D01*
G03X122949Y80952I-992J127D01*
G02X124248Y82251I-191J1490D01*
G03X125367Y81132I992J-127D01*
G37*
G36*
G01X111039Y142540D02*
G02X110019Y145160I-2439J559D01*
G03X111561Y145760I567J824D01*
G02X112581Y143140I2439J-559D01*
G03X111039Y142540I-567J-824D01*
G37*
G36*
G01X101326Y147979D02*
G02X100603Y150821I-2326J921D01*
G03X102174Y151221I641J768D01*
G02X102897Y148379I2326J-921D01*
G03X101326Y147979I-641J-768D01*
G37*
G36*
G01X91373Y150992D02*
G02X89199Y152694I-2373J-792D01*
G03X90227Y154008I79J997D01*
G02X93994Y156878I2373J792D01*
G03X95536Y157534I557J830D01*
G02X96606Y155022I2464J-434D01*
G03X95064Y154366I-557J-830D01*
G02X92401Y152306I-2464J434D01*
G03X91373Y150992I-79J-997D01*
G37*
G36*
G01X120540Y153296D02*
G02X117760Y154419I-2140J-1296D01*
G03X118360Y155904I-255J967D01*
G02X118234Y158260I2140J1296D01*
G03X117548Y159660I-906J424D01*
G02X120366Y161040I552J2440D01*
G03X121052Y159640I906J-424D01*
G02X121140Y154781I-552J-2440D01*
G03X120540Y153296I255J-967D01*
G37*
G36*
G01X81167Y158811D02*
G02X78434Y160475I-2367J-811D01*
G03X79233Y161789I-147J989D01*
G02X81966Y160125I2367J811D01*
G03X81167Y158811I147J-989D01*
G37*
G36*
G01X112694Y160944D02*
G02X109820Y161457I-1794J-1744D01*
G03X110106Y163056I-431J902D01*
G02X112980Y162543I1794J1744D01*
G03X112694Y160944I431J-902D01*
G37*
G36*
G01X66281Y162808D02*
G02X63939Y162271I-680J-2408D01*
G03X63764Y163890I-664J747D01*
G02X65732Y164341I736J1310D01*
G03X66281Y162808I821J-571D01*
G37*
G36*
G01X85652Y69147D02*
G03X85124Y68681I-29J-499D01*
G02X81712Y72093I-3195J217D01*
G03X82177Y72620I-34J499D01*
G02X82178Y73049I3689J206D01*
G03X81712Y73577I-499J29D01*
G02X85124Y76988I217J3195D01*
G03X85652Y76523I499J34D01*
G02X86080I214J-3688D01*
G03X86608Y76988I29J499D01*
G02X90020Y73577I3195J-216D01*
G03X89554Y73049I33J-499D01*
G02X89560Y72835I-3688J-210D01*
G02X89554Y72620I-3694J-4D01*
G03X90020Y72093I499J-28D01*
G02X86608Y68681I-217J-3195D01*
G03X86080Y69147I-499J-33D01*
G02X85652I-214J3688D01*
G37*
G36*
G01X87128Y106606D02*
G02X88120Y105632I-1261J-2276D01*
G01X88187Y105515D01*
X88418Y105382D01*
X89408D01*
G02X89560Y104331I-3542J-1049D01*
G02X89554Y104116I-3694J-4D01*
G03X90020Y103589I499J-28D01*
G02X86608Y100177I-217J-3195D01*
G03X86080Y100643I-499J-33D01*
G02X85652I-214J3688D01*
G03X85124Y100177I-29J-499D01*
G02X81712Y103589I-3195J217D01*
G03X82177Y104116I-34J499D01*
G02X82178Y104545I3689J206D01*
G03X81712Y105073I-499J29D01*
G02X85124Y108484I217J3195D01*
G03X85652Y108019I499J34D01*
G02X86870Y107886I214J-3688D01*
G01Y107044D01*
G03X87128Y106606I500J0D01*
G37*
G36*
G01X1092722Y30690D02*
G03X1092118Y32095I-1934J1D01*
G02X1111112I9497J10031D01*
G03X1110508Y30690I1330J-1404D01*
G01Y18504D01*
G02X1092722I-8893J0D01*
G01Y30690D01*
G37*
G54D27*
X1487600Y147000D03*
X1495800Y147800D03*
X1492042Y126358D03*
X1492300Y117558D03*
X106958Y82142D03*
X112158Y82342D03*
X117158Y82542D03*
X106958Y68500D03*
X116958Y68600D03*
X121958Y70900D03*
X111958Y73600D03*
G54D28*
X1157000Y189800D03*
X1155400Y152400D03*
X1127000Y189800D03*
X1125400Y152400D03*
X1097000Y189800D03*
X1095400Y152400D03*
X1067000Y189800D03*
X1065400Y152400D03*
X1037000Y189800D03*
X1035400Y152400D03*
X1007000Y189800D03*
X1005400Y152400D03*
X977000Y189800D03*
X975400Y152400D03*
X947000Y189800D03*
X945400Y152400D03*
X917000Y189800D03*
X915400Y152400D03*
X887000Y189800D03*
X885400Y152400D03*
X857000Y189800D03*
X855400Y152400D03*
X350200Y181100D03*
X350000Y161800D03*
X300300Y140000D03*
X307800Y101100D03*
X281000Y180700D03*
X280000Y159800D03*
X267700Y145200D03*
X281800Y100900D03*
X273300Y94900D03*
X283600Y69500D03*
X268300Y36200D03*
X252800Y179900D03*
X252200Y159400D03*
X251600Y100100D03*
X254400Y74300D03*
X244900Y36600D03*
X257800Y51200D03*
X254400Y19200D03*
X216400Y100500D03*
X229200Y30900D03*
X225800Y19600D03*
X206700Y72700D03*
X195600Y64100D03*
X214700Y35800D03*
X197800Y48000D03*
Y30900D03*
X194400Y20200D03*
X181400Y84700D03*
X174300Y73300D03*
X184100Y36600D03*
X158200Y102400D03*
X161800Y86800D03*
X159800Y65100D03*
X151500Y35800D03*
X168100Y48400D03*
X165600Y19400D03*
X126600Y149500D03*
X129200Y142400D03*
Y101300D03*
X131400Y91300D03*
X139800Y90200D03*
X144100Y72900D03*
X138700Y63500D03*
X123900Y41000D03*
X104900Y157400D03*
X111800Y151800D03*
X119900Y143200D03*
X102000Y141900D03*
X121200Y33900D03*
X107200Y19300D03*
X102500Y29400D03*
X88000Y158900D03*
X100700Y163400D03*
X93900Y162900D03*
X83800Y154500D03*
X94900Y144500D03*
X90200Y22400D03*
X73200Y162100D03*
X76900Y20200D03*
X51900Y162300D03*
X813700Y43900D03*
X809700Y86500D03*
X839700D03*
X869700D03*
X899700D03*
X929700D03*
X959000Y18000D03*
X959700Y86500D03*
X989700D03*
X1043000Y45500D03*
X1031900Y84100D03*
X1063700Y15300D03*
X1061900Y84100D03*
X1073000Y45500D03*
X1091900Y84100D03*
X1120900Y64500D03*
X1121900Y84100D03*
X1147100Y64500D03*
X1151900Y84100D03*
G54D32*
X44528Y135827D03*
Y124016D03*
Y112205D03*
Y100394D03*
Y88583D03*
Y76772D03*
Y64961D03*
Y53150D03*
Y41339D03*
G54D31*
X89803Y84646D03*
Y92520D03*
X81929Y84646D03*
Y92520D03*
G54D29*
X359528Y59054D03*
X367402D03*
X359528Y51180D03*
Y43306D03*
X367402Y51180D03*
Y43306D03*
X359528Y27558D03*
Y19684D03*
Y11810D03*
X367402Y27558D03*
Y19684D03*
Y11810D03*
X1229606D03*
Y19684D03*
Y27558D03*
Y43306D03*
Y51180D03*
Y59054D03*
X1237480Y11810D03*
Y19684D03*
Y27558D03*
Y43306D03*
Y51180D03*
Y59054D03*
G54D30*
X119288Y103958D03*
X109288D03*
X119288Y92458D03*
X109288D03*
X19088Y80158D03*
Y91958D03*
G54D36*
X40827Y147638D03*
Y29528D03*
G54D33*
X1378938Y176650D03*
G54D37*
X1221732Y37400D03*
G54D34*
X1333938Y176650D03*
G54D35*
X351654Y37401D03*
%LPD*%
G75*
G54D10*
X56339Y41339D03*
Y53150D03*
Y64961D03*
Y76772D03*
Y88583D03*
Y100394D03*
Y112205D03*
Y124016D03*
Y135827D03*
G54D11*
X89803Y108268D03*
G54D20*
X482402Y29922D03*
Y18898D03*
Y13386D03*
Y46457D03*
X474528Y41339D03*
X482402Y40945D03*
X490276Y41339D03*
X482402Y35433D03*
X506024Y8268D03*
X498150Y29922D03*
X506024Y13780D03*
X498150Y46457D03*
Y35433D03*
X649173Y29922D03*
Y51969D03*
Y46457D03*
Y35433D03*
X657047Y8268D03*
X672795Y30315D03*
Y24803D03*
X657047Y13780D03*
X664921Y51969D03*
Y46457D03*
X688543Y8268D03*
X680669Y29922D03*
X688543Y13780D03*
X680669Y51969D03*
Y46457D03*
X688543Y46851D03*
Y41339D03*
X680669Y35433D03*
X1344607Y41339D03*
X1352481Y29922D03*
Y18898D03*
Y13386D03*
Y46457D03*
Y40945D03*
X1360355Y41339D03*
X1352481Y35433D03*
X1376103Y8268D03*
X1368229Y29922D03*
X1376103Y13780D03*
X1368229Y46457D03*
Y35433D03*
X1527126Y8268D03*
X1519252Y29922D03*
X1527126Y13780D03*
X1519252Y51969D03*
Y46457D03*
Y35433D03*
X1542874Y30315D03*
X1550748Y29922D03*
X1542874Y24803D03*
X1535000Y51969D03*
X1550748D03*
X1535000Y46457D03*
X1550748D03*
Y35433D03*
X1558622Y8268D03*
Y13780D03*
Y46851D03*
Y41339D03*
G54D21*
X639283Y167677D03*
X793693Y108622D03*
Y167677D03*
X1509362D03*
X1663772Y108622D03*
Y167677D03*
G54D12*
X99100Y127470D03*
X120500Y59400D03*
X114400Y59700D03*
X107500Y59500D03*
X102400Y59600D03*
X102590Y115680D03*
X115400Y120270D03*
X107390Y125110D03*
X119800Y124390D03*
X108900Y137300D03*
X114300Y134900D03*
X119700Y132400D03*
X111500Y129900D03*
X128600Y114510D03*
X132500Y110100D03*
X125000Y126400D03*
X141400Y164800D03*
X129000D03*
X169200Y165200D03*
X155500Y164800D03*
X183300Y164700D03*
X346800Y113500D03*
X345400Y107600D03*
X346200Y102500D03*
X357800Y114657D03*
X357600Y108561D03*
X356861Y102961D03*
X400100Y13900D03*
X412800Y16200D03*
X410906Y46100D03*
X414055Y46200D03*
X412480Y80900D03*
X403032Y89532D03*
X415630Y80700D03*
X412300Y85600D03*
X421929Y78400D03*
X409331Y88600D03*
X406181Y82300D03*
X399882Y79318D03*
X453900Y92300D03*
X466200Y87558D03*
X453300Y86800D03*
X451100Y81400D03*
X452100Y97000D03*
X466100Y83258D03*
X452000Y102200D03*
X488800Y73700D03*
X525700Y99300D03*
X519400Y96400D03*
X520439Y91000D03*
X516500Y87442D03*
X559425Y13575D03*
X560198Y46100D03*
X558623Y79200D03*
X552324Y78500D03*
X549174Y89400D03*
X582416Y16466D03*
X563347Y46100D03*
X571221Y79700D03*
X568072Y81500D03*
X564922Y81900D03*
X561772Y80800D03*
X563800Y87700D03*
X614900Y90157D03*
X615600Y95139D03*
X615500Y100157D03*
Y105157D03*
X659310Y72900D03*
X664310D03*
X654400Y92100D03*
Y97100D03*
X671063Y125930D03*
X676063D03*
X689961Y122030D03*
X694961D03*
X730310Y115390D03*
X725310D03*
X761929Y72900D03*
X756929D03*
X752480Y92830D03*
X747480D03*
X760410Y124730D03*
X755410D03*
X778200Y92130D03*
Y97130D03*
X1226900Y119561D03*
Y114043D03*
X1227000Y108361D03*
X1227100Y102861D03*
X1268700Y14000D03*
X1273111Y89100D03*
X1269961Y78400D03*
X1289775Y11975D03*
X1284134Y46100D03*
X1280985Y46200D03*
X1292008Y80192D03*
X1288859Y78400D03*
X1279410Y87200D03*
X1285709Y84300D03*
X1276260Y79000D03*
X1282559Y85700D03*
X1333400Y82900D03*
X1323000Y99239D03*
X1321400Y92800D03*
X1329500Y81400D03*
X1321500Y82600D03*
X1322500Y87800D03*
X1358200Y69000D03*
X1358600Y73700D03*
X1345100Y105500D03*
X1387400Y87242D03*
X1389900Y97600D03*
X1395200Y99500D03*
X1391000Y92400D03*
X1429525Y13775D03*
X1433426Y46100D03*
X1430277D03*
X1422403Y78400D03*
X1434200Y88100D03*
X1435001Y81700D03*
X1431851Y80200D03*
X1428702Y79002D03*
X1429400Y88500D03*
X1454600Y17600D03*
X1441300Y79100D03*
X1438151Y81100D03*
X1484700Y93057D03*
X1485000Y98057D03*
X1494700Y111200D03*
X1484900Y103257D03*
X1484800Y109357D03*
X1524478Y97100D03*
Y92100D03*
X1534388Y72900D03*
X1529388D03*
X1546141Y125930D03*
X1541141D03*
X1565039Y122030D03*
X1560039D03*
X1595388Y115390D03*
X1617558Y92830D03*
X1600388Y115390D03*
X1627007Y72900D03*
X1632007D03*
X1622558Y92830D03*
X1625488Y124730D03*
X1630488D03*
X1648278Y97130D03*
Y92130D03*
G54D22*
X791764Y132244D03*
X1511291D03*
X1661843D03*
G54D13*
X123100Y49600D03*
X143300Y27300D03*
X143800Y53600D03*
X144500Y40000D03*
X133100Y71300D03*
X144200Y96300D03*
X143000Y105700D03*
X141900Y154700D03*
X134800Y164000D03*
X144700Y149200D03*
X137100Y158600D03*
X137000Y170400D03*
X127400D03*
X150300Y20200D03*
X166500Y34700D03*
X153100Y49600D03*
X148800Y85000D03*
X163500Y144900D03*
X150300Y144600D03*
X156000Y138200D03*
X156500Y144800D03*
X169900Y146800D03*
X164400Y138200D03*
X169400Y153600D03*
X155600Y157900D03*
X162100Y164300D03*
X168000Y161200D03*
X149300Y164100D03*
X163200Y151600D03*
X162000Y159400D03*
X148000Y158800D03*
X152600Y152000D03*
X155900Y170000D03*
X163800Y170100D03*
X148600D03*
X180300Y20200D03*
X183100Y49600D03*
X191700Y75400D03*
X175000Y62300D03*
X174200Y96300D03*
X190400Y136600D03*
X191200Y142400D03*
X178100Y144600D03*
X184000Y138800D03*
X173600Y138700D03*
X185800Y145400D03*
X190000Y149800D03*
X179300Y156400D03*
X187100Y155800D03*
X192100Y163500D03*
X176300Y164400D03*
X175500Y151300D03*
X173700Y158700D03*
X190400Y169800D03*
X182600Y152000D03*
X171300Y170000D03*
X177800Y170400D03*
X210300Y20200D03*
X213100Y49600D03*
X209400Y60900D03*
X204200Y96300D03*
X196200Y102300D03*
X211300Y138600D03*
X204200Y139200D03*
X195900Y146300D03*
X213300Y146800D03*
X197300Y139100D03*
X205100Y147700D03*
X201500Y154400D03*
X213500Y155400D03*
X197100Y160800D03*
X194600Y154800D03*
X227100Y43000D03*
X234200Y96300D03*
X225600Y104500D03*
X234500Y138700D03*
X230600Y146400D03*
X218100Y140500D03*
X224400Y138200D03*
X236800Y165000D03*
X238800Y157500D03*
X231600Y155100D03*
X221800Y149400D03*
X236500Y185900D03*
X235400Y172900D03*
X240300Y20200D03*
X243100Y49600D03*
X248600Y142900D03*
X242600Y140100D03*
X254400Y138200D03*
X239600Y148700D03*
X245100Y165200D03*
X255400Y148400D03*
X245600Y157000D03*
X248400Y149800D03*
X239800Y178700D03*
X243300Y185600D03*
X242300Y171800D03*
X252600Y192000D03*
X242400Y193300D03*
X270300Y20200D03*
X273100Y49600D03*
X264200Y96300D03*
X262900Y104900D03*
X284400Y138200D03*
X265300Y170000D03*
X282600Y192000D03*
X294200Y96300D03*
X287600Y150000D03*
X292800Y169800D03*
X324200Y96300D03*
X314600Y104100D03*
X310200Y135900D03*
X338300Y162900D03*
Y183800D03*
X359200Y164900D03*
X359100Y184400D03*
X806800Y26700D03*
X810700Y65200D03*
X836800Y26700D03*
X825200Y111700D03*
X840700Y65200D03*
X855200Y111700D03*
X855400Y173000D03*
X866800Y26700D03*
X870700Y65200D03*
X896800Y26700D03*
X900700Y65200D03*
X885200Y111700D03*
X885400Y173000D03*
X926800Y26700D03*
X915200Y111700D03*
X915400Y173000D03*
X930700Y65200D03*
X945200Y111700D03*
X945400Y173000D03*
X956800Y26700D03*
X960700Y65200D03*
X975200Y111700D03*
X975400Y173000D03*
X986800Y26700D03*
X990700Y65200D03*
X1018800Y26300D03*
X1005200Y111700D03*
X1005400Y173000D03*
X1022700Y64800D03*
X1037200Y111300D03*
X1035400Y173000D03*
X1048800Y26300D03*
X1052700Y64800D03*
X1067200Y111300D03*
X1067400Y172600D03*
X1078800Y26300D03*
X1082700Y64800D03*
X1097200Y111300D03*
X1097400Y172600D03*
X1136600Y19700D03*
X1135400Y41000D03*
X1127200Y111300D03*
X1127400Y172600D03*
X1157400D03*
G54D23*
G01X1358600Y73700D02*
X1352300Y80000D01*
Y98300D01*
X1345100Y105500D01*
G54D14*
X306772Y19685D03*
Y41850D03*
X1176851Y19685D03*
Y41850D03*
G54D24*
G01X410906Y46100D02*
Y47200D01*
X409306Y48800D01*
X397300D01*
X393700Y45200D01*
Y39500D01*
X388400Y34200D01*
Y24800D01*
X399300Y13900D01*
X400100D01*
G01X414055Y46200D02*
Y48845D01*
X411000Y51900D01*
X396000D01*
X390700Y46600D01*
Y40900D01*
X385300Y35500D01*
Y23400D01*
X397900Y10800D01*
X407400D01*
X412800Y16200D01*
G01X582416Y16466D02*
X576350Y10400D01*
X553500D01*
X534900Y29000D01*
Y35500D01*
X539900Y40500D01*
Y46400D01*
X545400Y51900D01*
X559600D01*
X563347Y48153D01*
Y46100D01*
G01X559425Y13575D02*
X554625D01*
X537900Y30300D01*
Y34000D01*
X543000Y39100D01*
Y45200D01*
X546300Y48500D01*
X558500D01*
X560198Y46802D01*
Y46100D01*
G01X1289775Y11975D02*
X1288500Y10700D01*
X1267500D01*
X1254979Y23221D01*
Y35000D01*
X1260979Y41000D01*
Y46700D01*
X1266079Y51800D01*
X1281079D01*
X1284134Y48745D01*
Y46100D01*
G01X1268700Y14000D02*
X1258079Y24621D01*
Y33700D01*
X1264379Y40000D01*
Y45700D01*
X1267379Y48700D01*
X1279385D01*
X1280985Y47100D01*
Y46200D01*
G01X1454600Y17600D02*
X1447700Y10700D01*
X1423279D01*
X1404979Y29000D01*
Y35500D01*
X1409979Y40500D01*
Y46400D01*
X1415479Y51900D01*
X1429679D01*
X1433426Y48153D01*
Y46100D01*
G01X1429525Y13775D02*
X1424504D01*
X1407979Y30300D01*
Y34000D01*
X1413079Y39100D01*
Y45200D01*
X1416379Y48500D01*
X1428579D01*
X1430277Y46802D01*
Y46100D01*
G54D15*
X306772Y67913D03*
X1176851D03*
G54D25*
G01X457212Y-338900D02*
Y-343900D01*
G01X455755Y-338900D02*
X458669D01*
G01X463579Y-343900D02*
X461045D01*
Y-338900D01*
X463579D01*
G01X462565Y-341317D02*
X461045D01*
G01X466145Y-338900D02*
Y-343900D01*
X468679D01*
G01X472512Y-344067D02*
X472385Y-343983D01*
Y-343817D01*
X472512Y-343733D01*
X472639Y-343817D01*
Y-343983D01*
X472512Y-344067D01*
G01Y-341817D02*
X472385Y-341733D01*
Y-341567D01*
X472512Y-341483D01*
X472639Y-341567D01*
Y-341733D01*
X472512Y-341817D01*
G01X477295Y-345567D02*
X476662Y-344733D01*
X476345Y-343900D01*
Y-340567D01*
X476662Y-339733D01*
X477295Y-338900D01*
G01X482712D02*
X482205Y-339067D01*
X481825Y-339483D01*
X481572Y-339983D01*
X481382Y-340650D01*
X481319Y-341400D01*
X481382Y-342150D01*
X481572Y-342817D01*
X481825Y-343317D01*
X482205Y-343733D01*
X482712Y-343900D01*
X483219Y-343733D01*
X483599Y-343317D01*
X483852Y-342817D01*
X484042Y-342150D01*
X484105Y-341400D01*
X484042Y-340650D01*
X483852Y-339983D01*
X483599Y-339483D01*
X483219Y-339067D01*
X482712Y-338900D01*
G01X486419Y-342900D02*
X486799Y-343483D01*
X487305Y-343817D01*
X487875Y-343900D01*
X488382Y-343817D01*
X488889Y-343400D01*
X489205Y-342900D01*
X489269Y-342400D01*
X489142Y-341817D01*
X488699Y-341400D01*
X488255Y-341233D01*
X487685D01*
G01X488255D02*
X488635Y-340983D01*
X488952Y-340567D01*
X489079Y-340067D01*
X488952Y-339567D01*
X488635Y-339150D01*
X488065Y-338900D01*
X487495Y-338983D01*
X486925Y-339317D01*
G01X493229Y-345567D02*
X493862Y-344733D01*
X494179Y-343900D01*
Y-340567D01*
X493862Y-339733D01*
X493229Y-338900D01*
G01X496619Y-342900D02*
X496999Y-343483D01*
X497505Y-343817D01*
X498075Y-343900D01*
X498582Y-343817D01*
X499089Y-343400D01*
X499405Y-342900D01*
X499469Y-342400D01*
X499342Y-341817D01*
X498899Y-341400D01*
X498455Y-341233D01*
X497885D01*
G01X498455D02*
X498835Y-340983D01*
X499152Y-340567D01*
X499279Y-340067D01*
X499152Y-339567D01*
X498835Y-339150D01*
X498265Y-338900D01*
X497695Y-338983D01*
X497125Y-339317D01*
G01X501909Y-339733D02*
X502289Y-339233D01*
X502732Y-338983D01*
X503239Y-338900D01*
X503872Y-339067D01*
X504315Y-339483D01*
X504442Y-339983D01*
X504379Y-340483D01*
X504125Y-340900D01*
X502859Y-341733D01*
X502289Y-342317D01*
X501909Y-343150D01*
X501782Y-343900D01*
X504442D01*
G01X508085D02*
X508212Y-342817D01*
X508402Y-341900D01*
X508655Y-341067D01*
X508972Y-340150D01*
X509479Y-338900D01*
X506945D01*
G01X512489Y-342233D02*
X514135D01*
G01X517209Y-339733D02*
X517589Y-339233D01*
X518032Y-338983D01*
X518539Y-338900D01*
X519172Y-339067D01*
X519615Y-339483D01*
X519742Y-339983D01*
X519679Y-340483D01*
X519425Y-340900D01*
X518159Y-341733D01*
X517589Y-342317D01*
X517209Y-343150D01*
X517082Y-343900D01*
X519742D01*
G01X522119Y-342900D02*
X522499Y-343483D01*
X523005Y-343817D01*
X523575Y-343900D01*
X524082Y-343817D01*
X524589Y-343400D01*
X524905Y-342900D01*
X524969Y-342400D01*
X524842Y-341817D01*
X524399Y-341400D01*
X523955Y-341233D01*
X523385D01*
G01X523955D02*
X524335Y-340983D01*
X524652Y-340567D01*
X524779Y-340067D01*
X524652Y-339567D01*
X524335Y-339150D01*
X523765Y-338900D01*
X523195Y-338983D01*
X522625Y-339317D01*
G01X529372Y-343900D02*
Y-338900D01*
X527029Y-342483D01*
X530195D01*
G01X532319Y-343150D02*
X532699Y-343567D01*
X533142Y-343817D01*
X533712Y-343900D01*
X534282Y-343733D01*
X534725Y-343400D01*
X535042Y-342817D01*
X535105Y-342150D01*
X534979Y-341483D01*
X534662Y-341067D01*
X534219Y-340733D01*
X533775Y-340650D01*
X533332Y-340733D01*
X532762Y-341067D01*
X532952Y-338900D01*
X534662D01*
G01X542709Y-343900D02*
Y-338900D01*
X545115D01*
G01X544229Y-341317D02*
X542709D01*
G01X547429Y-343900D02*
X549012Y-338900D01*
X550595Y-343900D01*
G01X550025Y-342150D02*
X547999D01*
G01X552782Y-343900D02*
X555442Y-338900D01*
G01X552782D02*
X555442Y-343900D01*
G01X559212Y-344067D02*
X559085Y-343983D01*
Y-343817D01*
X559212Y-343733D01*
X559339Y-343817D01*
Y-343983D01*
X559212Y-344067D01*
G01Y-341817D02*
X559085Y-341733D01*
Y-341567D01*
X559212Y-341483D01*
X559339Y-341567D01*
Y-341733D01*
X559212Y-341817D01*
G01X563995Y-345567D02*
X563362Y-344733D01*
X563045Y-343900D01*
Y-340567D01*
X563362Y-339733D01*
X563995Y-338900D01*
G01X569412D02*
X568905Y-339067D01*
X568525Y-339483D01*
X568272Y-339983D01*
X568082Y-340650D01*
X568019Y-341400D01*
X568082Y-342150D01*
X568272Y-342817D01*
X568525Y-343317D01*
X568905Y-343733D01*
X569412Y-343900D01*
X569919Y-343733D01*
X570299Y-343317D01*
X570552Y-342817D01*
X570742Y-342150D01*
X570805Y-341400D01*
X570742Y-340650D01*
X570552Y-339983D01*
X570299Y-339483D01*
X569919Y-339067D01*
X569412Y-338900D01*
G01X573119Y-342900D02*
X573499Y-343483D01*
X574005Y-343817D01*
X574575Y-343900D01*
X575082Y-343817D01*
X575589Y-343400D01*
X575905Y-342900D01*
X575969Y-342400D01*
X575842Y-341817D01*
X575399Y-341400D01*
X574955Y-341233D01*
X574385D01*
G01X574955D02*
X575335Y-340983D01*
X575652Y-340567D01*
X575779Y-340067D01*
X575652Y-339567D01*
X575335Y-339150D01*
X574765Y-338900D01*
X574195Y-338983D01*
X573625Y-339317D01*
G01X579929Y-345567D02*
X580562Y-344733D01*
X580879Y-343900D01*
Y-340567D01*
X580562Y-339733D01*
X579929Y-338900D01*
G01X583319Y-342900D02*
X583699Y-343483D01*
X584205Y-343817D01*
X584775Y-343900D01*
X585282Y-343817D01*
X585789Y-343400D01*
X586105Y-342900D01*
X586169Y-342400D01*
X586042Y-341817D01*
X585599Y-341400D01*
X585155Y-341233D01*
X584585D01*
G01X585155D02*
X585535Y-340983D01*
X585852Y-340567D01*
X585979Y-340067D01*
X585852Y-339567D01*
X585535Y-339150D01*
X584965Y-338900D01*
X584395Y-338983D01*
X583825Y-339317D01*
G01X588735Y-343317D02*
X589179Y-343733D01*
X589685Y-343900D01*
X590192Y-343733D01*
X590635Y-343233D01*
X590952Y-342483D01*
X591079Y-341733D01*
Y-340817D01*
X590952Y-340067D01*
X590635Y-339400D01*
X590255Y-339067D01*
X589812Y-338900D01*
X589305Y-339067D01*
X588925Y-339400D01*
X588672Y-339900D01*
X588545Y-340567D01*
X588672Y-341150D01*
X588989Y-341733D01*
X589369Y-342067D01*
X589812Y-342150D01*
X590319Y-341983D01*
X590699Y-341567D01*
X591079Y-340817D01*
G01X594785Y-343900D02*
X594912Y-342817D01*
X595102Y-341900D01*
X595355Y-341067D01*
X595672Y-340150D01*
X596179Y-338900D01*
X593645D01*
G01X599189Y-342233D02*
X600835D01*
G01X603719Y-342900D02*
X604099Y-343483D01*
X604605Y-343817D01*
X605175Y-343900D01*
X605682Y-343817D01*
X606189Y-343400D01*
X606505Y-342900D01*
X606569Y-342400D01*
X606442Y-341817D01*
X605999Y-341400D01*
X605555Y-341233D01*
X604985D01*
G01X605555D02*
X605935Y-340983D01*
X606252Y-340567D01*
X606379Y-340067D01*
X606252Y-339567D01*
X605935Y-339150D01*
X605365Y-338900D01*
X604795Y-338983D01*
X604225Y-339317D01*
G01X609009Y-341817D02*
X609452Y-341233D01*
X609832Y-340900D01*
X610339Y-340733D01*
X610782Y-340900D01*
X611099Y-341233D01*
X611352Y-341733D01*
X611415Y-342317D01*
X611352Y-342817D01*
X611099Y-343317D01*
X610719Y-343733D01*
X610275Y-343900D01*
X609769Y-343733D01*
X609325Y-343233D01*
X609072Y-342483D01*
X609009Y-341650D01*
X609135Y-340567D01*
X609325Y-339983D01*
X609642Y-339400D01*
X610085Y-338983D01*
X610529Y-338900D01*
X610972Y-339067D01*
X611289Y-339483D01*
G01X615312Y-343900D02*
Y-338900D01*
X614552Y-339900D01*
G01Y-343900D02*
X616072D01*
G01X621172D02*
Y-338900D01*
X618829Y-342483D01*
X621995D01*
G01X445212Y-273900D02*
Y-348900D01*
X945212D01*
Y-273900D01*
X445212D01*
G01X640212D02*
Y-348900D01*
G01Y-323900D02*
X743212D01*
Y-298900D01*
G01X640212D02*
X743212D01*
G01Y-273900D02*
Y-348900D01*
G01X745212Y-273900D02*
Y-348900D01*
G01X750719Y-333900D02*
Y-328900D01*
X751985D01*
X752492Y-329150D01*
X752872Y-329483D01*
X753189Y-329983D01*
X753442Y-330567D01*
X753505Y-331400D01*
X753442Y-332233D01*
X753189Y-332817D01*
X752872Y-333317D01*
X752492Y-333650D01*
X751985Y-333900D01*
X750719D01*
G01X755629D02*
X757212Y-328900D01*
X758795Y-333900D01*
G01X758225Y-332150D02*
X756199D01*
G01X762312Y-328900D02*
Y-333900D01*
G01X760855Y-328900D02*
X763769D01*
G01X768679Y-333900D02*
X766145D01*
Y-328900D01*
X768679D01*
G01X767665Y-331317D02*
X766145D01*
G01X772512Y-334067D02*
X772385Y-333983D01*
Y-333817D01*
X772512Y-333733D01*
X772639Y-333817D01*
Y-333983D01*
X772512Y-334067D01*
G01Y-331817D02*
X772385Y-331733D01*
Y-331567D01*
X772512Y-331483D01*
X772639Y-331567D01*
Y-331733D01*
X772512Y-331817D01*
G01X745212Y-323900D02*
X945212D01*
G01X750845Y-308900D02*
Y-303900D01*
X752365D01*
X752872Y-304150D01*
X753252Y-304733D01*
X753379Y-305400D01*
X753252Y-306067D01*
X752935Y-306567D01*
X752365Y-306817D01*
X750845D01*
G01X756072Y-309067D02*
X758352Y-303900D01*
G01X760855Y-308900D02*
Y-303900D01*
X763769Y-308900D01*
Y-303900D01*
G01X767412Y-309067D02*
X767285Y-308983D01*
Y-308817D01*
X767412Y-308733D01*
X767539Y-308817D01*
Y-308983D01*
X767412Y-309067D01*
G01Y-306817D02*
X767285Y-306733D01*
Y-306567D01*
X767412Y-306483D01*
X767539Y-306567D01*
Y-306733D01*
X767412Y-306817D01*
G01X745212Y-298900D02*
X945212D01*
G01X750845Y-283900D02*
Y-278900D01*
X752365D01*
X752872Y-279150D01*
X753252Y-279733D01*
X753379Y-280400D01*
X753252Y-281067D01*
X752935Y-281567D01*
X752365Y-281817D01*
X750845D01*
G01X755945Y-283900D02*
Y-278900D01*
X757529D01*
X758035Y-279150D01*
X758352Y-279483D01*
X758479Y-280150D01*
X758352Y-280817D01*
X757972Y-281233D01*
X757529Y-281483D01*
X755945D01*
G01X757529D02*
X758479Y-283900D01*
G01X762312D02*
X761805Y-283817D01*
X761362Y-283483D01*
X760982Y-282983D01*
X760729Y-282400D01*
X760602Y-281733D01*
Y-281067D01*
X760729Y-280400D01*
X760982Y-279817D01*
X761362Y-279317D01*
X761805Y-278983D01*
X762312Y-278900D01*
X762819Y-278983D01*
X763262Y-279317D01*
X763642Y-279817D01*
X763895Y-280400D01*
X764022Y-281067D01*
Y-281733D01*
X763895Y-282400D01*
X763642Y-282983D01*
X763262Y-283483D01*
X762819Y-283817D01*
X762312Y-283900D01*
G01X766145Y-282900D02*
X766462Y-283400D01*
X766842Y-283733D01*
X767285Y-283900D01*
X767792Y-283733D01*
X768172Y-283400D01*
X768552Y-282900D01*
X768679Y-282233D01*
Y-278900D01*
G01X773779Y-283900D02*
X771245D01*
Y-278900D01*
X773779D01*
G01X772765Y-281317D02*
X771245D01*
G01X779005Y-279317D02*
X778625Y-279067D01*
X778182Y-278900D01*
X777675D01*
X777105Y-279150D01*
X776662Y-279567D01*
X776345Y-280067D01*
X776092Y-280900D01*
X776029Y-281650D01*
X776155Y-282400D01*
X776345Y-282900D01*
X776725Y-283400D01*
X777169Y-283733D01*
X777612Y-283900D01*
X778055D01*
X778499Y-283733D01*
X778879Y-283483D01*
X779195Y-283150D01*
G01X782712Y-278900D02*
Y-283900D01*
G01X781255Y-278900D02*
X784169D01*
G01X787812Y-284067D02*
X787685Y-283983D01*
Y-283817D01*
X787812Y-283733D01*
X787939Y-283817D01*
Y-283983D01*
X787812Y-284067D01*
G01Y-281817D02*
X787685Y-281733D01*
Y-281567D01*
X787812Y-281483D01*
X787939Y-281567D01*
Y-281733D01*
X787812Y-281817D01*
G01X860212Y-323900D02*
Y-348900D01*
G01X865845Y-333900D02*
Y-328900D01*
X867429D01*
X867935Y-329150D01*
X868252Y-329483D01*
X868379Y-330150D01*
X868252Y-330817D01*
X867872Y-331233D01*
X867429Y-331483D01*
X865845D01*
G01X867429D02*
X868379Y-333900D01*
G01X873479D02*
X870945D01*
Y-328900D01*
X873479D01*
G01X872465Y-331317D02*
X870945D01*
G01X875729Y-328900D02*
X877312Y-333900D01*
X878895Y-328900D01*
G01X882412Y-334067D02*
X882285Y-333983D01*
Y-333817D01*
X882412Y-333733D01*
X882539Y-333817D01*
Y-333983D01*
X882412Y-334067D01*
G01Y-331817D02*
X882285Y-331733D01*
Y-331567D01*
X882412Y-331483D01*
X882539Y-331567D01*
Y-331733D01*
X882412Y-331817D01*
G01X909212Y-323900D02*
Y-348900D01*
G01X-471400Y-391900D02*
Y1528800D01*
X2244200D01*
Y-391900D01*
X-471400D01*
G01X455917Y-335560D02*
X456544Y-336085D01*
X457249Y-336400D01*
X457875D01*
X458502Y-336085D01*
X458972Y-335560D01*
X459207Y-334825D01*
X459050Y-334090D01*
X458659Y-333460D01*
X457954Y-333040D01*
X457014Y-332830D01*
X456465Y-332410D01*
X456230Y-331675D01*
X456387Y-330940D01*
X456779Y-330415D01*
X457327Y-330100D01*
X457875D01*
X458424Y-330310D01*
X458894Y-330835D01*
G01X462217Y-336400D02*
Y-330100D01*
G01X465507D02*
Y-336400D01*
G01Y-333250D02*
X462217D01*
G01X469222Y-330100D02*
X471102D01*
G01X470162D02*
Y-336400D01*
G01X469222D02*
X471102D01*
G01X478029D02*
X474895D01*
Y-330100D01*
X478029D01*
G01X476775Y-333145D02*
X474895D01*
G01X480960Y-336400D02*
Y-330100D01*
X484564Y-336400D01*
Y-330100D01*
G01X488905Y-337555D02*
X489219Y-336190D01*
G01X495362Y-330100D02*
Y-336400D01*
G01X493560Y-330100D02*
X497164D01*
G01X499704Y-336400D02*
X501662Y-330100D01*
X503620Y-336400D01*
G01X502915Y-334195D02*
X500409D01*
G01X507022Y-330100D02*
X508902D01*
G01X507962D02*
Y-336400D01*
G01X507022D02*
X508902D01*
G01X511912Y-330100D02*
X513009Y-336400D01*
X514262Y-330100D01*
X515515Y-336400D01*
X516612Y-330100D01*
G01X518604Y-336400D02*
X520562Y-330100D01*
X522520Y-336400D01*
G01X521815Y-334195D02*
X519309D01*
G01X525060Y-336400D02*
Y-330100D01*
X528664Y-336400D01*
Y-330100D01*
G01X537895Y-336400D02*
Y-330100D01*
X539854D01*
X540480Y-330415D01*
X540872Y-330835D01*
X541029Y-331675D01*
X540872Y-332515D01*
X540402Y-333040D01*
X539854Y-333355D01*
X537895D01*
G01X539854D02*
X541029Y-336400D01*
G01X545762Y-336610D02*
X545605Y-336505D01*
Y-336295D01*
X545762Y-336190D01*
X545919Y-336295D01*
Y-336505D01*
X545762Y-336610D01*
G01X552062Y-336400D02*
X551435Y-336295D01*
X550887Y-335875D01*
X550417Y-335245D01*
X550104Y-334510D01*
X549947Y-333670D01*
Y-332830D01*
X550104Y-331990D01*
X550417Y-331255D01*
X550887Y-330625D01*
X551435Y-330205D01*
X552062Y-330100D01*
X552689Y-330205D01*
X553237Y-330625D01*
X553707Y-331255D01*
X554020Y-331990D01*
X554177Y-332830D01*
Y-333670D01*
X554020Y-334510D01*
X553707Y-335245D01*
X553237Y-335875D01*
X552689Y-336295D01*
X552062Y-336400D01*
G01X558362Y-336610D02*
X558205Y-336505D01*
Y-336295D01*
X558362Y-336190D01*
X558519Y-336295D01*
Y-336505D01*
X558362Y-336610D01*
G01X566385Y-330625D02*
X565915Y-330310D01*
X565367Y-330100D01*
X564740D01*
X564035Y-330415D01*
X563487Y-330940D01*
X563095Y-331570D01*
X562782Y-332620D01*
X562704Y-333565D01*
X562860Y-334510D01*
X563095Y-335140D01*
X563565Y-335770D01*
X564114Y-336190D01*
X564662Y-336400D01*
X565210D01*
X565759Y-336190D01*
X566229Y-335875D01*
X566620Y-335455D01*
G01X570962Y-336610D02*
X570805Y-336505D01*
Y-336295D01*
X570962Y-336190D01*
X571119Y-336295D01*
Y-336505D01*
X570962Y-336610D01*
G01X455839Y-326400D02*
Y-320100D01*
G01X458815D02*
X455839Y-323985D01*
G01X459285Y-326400D02*
X457170Y-322200D01*
G01X462139Y-320100D02*
Y-324615D01*
X462452Y-325560D01*
X463079Y-326190D01*
X463862Y-326400D01*
X464645Y-326190D01*
X465272Y-325560D01*
X465585Y-324615D01*
Y-320100D01*
G01X471729Y-326400D02*
X468595D01*
Y-320100D01*
X471729D01*
G01X470475Y-323145D02*
X468595D01*
G01X475522Y-320100D02*
X477402D01*
G01X476462D02*
Y-326400D01*
G01X475522D02*
X477402D01*
G01X487417Y-325560D02*
X488044Y-326085D01*
X488749Y-326400D01*
X489375D01*
X490002Y-326085D01*
X490472Y-325560D01*
X490707Y-324825D01*
X490550Y-324090D01*
X490159Y-323460D01*
X489454Y-323040D01*
X488514Y-322830D01*
X487965Y-322410D01*
X487730Y-321675D01*
X487887Y-320940D01*
X488279Y-320415D01*
X488827Y-320100D01*
X489375D01*
X489924Y-320310D01*
X490394Y-320835D01*
G01X493717Y-326400D02*
Y-320100D01*
G01X497007D02*
Y-326400D01*
G01Y-323250D02*
X493717D01*
G01X499704Y-326400D02*
X501662Y-320100D01*
X503620Y-326400D01*
G01X502915Y-324195D02*
X500409D01*
G01X506160Y-326400D02*
Y-320100D01*
X509764Y-326400D01*
Y-320100D01*
G01X518917Y-326400D02*
Y-320100D01*
G01X522207D02*
Y-326400D01*
G01Y-323250D02*
X518917D01*
G01X525217Y-325560D02*
X525844Y-326085D01*
X526549Y-326400D01*
X527175D01*
X527802Y-326085D01*
X528272Y-325560D01*
X528507Y-324825D01*
X528350Y-324090D01*
X527959Y-323460D01*
X527254Y-323040D01*
X526314Y-322830D01*
X525765Y-322410D01*
X525530Y-321675D01*
X525687Y-320940D01*
X526079Y-320415D01*
X526627Y-320100D01*
X527175D01*
X527724Y-320310D01*
X528194Y-320835D01*
G01X532222Y-320100D02*
X534102D01*
G01X533162D02*
Y-326400D01*
G01X532222D02*
X534102D01*
G01X537504D02*
X539462Y-320100D01*
X541420Y-326400D01*
G01X540715Y-324195D02*
X538209D01*
G01X543960Y-326400D02*
Y-320100D01*
X547564Y-326400D01*
Y-320100D01*
G01X552532Y-323250D02*
X554099D01*
Y-325140D01*
X553629Y-325770D01*
X553080Y-326190D01*
X552297Y-326400D01*
X551514Y-326190D01*
X550965Y-325770D01*
X550495Y-325140D01*
X550182Y-324405D01*
X550025Y-323565D01*
Y-322830D01*
X550182Y-322200D01*
X550495Y-321465D01*
X550965Y-320835D01*
X551435Y-320415D01*
X552062Y-320100D01*
X552610D01*
X553237Y-320310D01*
X553707Y-320730D01*
G01X558205Y-327555D02*
X558519Y-326190D01*
G01X564662Y-320100D02*
Y-326400D01*
G01X562860Y-320100D02*
X566464D01*
G01X569004Y-326400D02*
X570962Y-320100D01*
X572920Y-326400D01*
G01X572215Y-324195D02*
X569709D01*
G01X577262Y-326400D02*
X576635Y-326295D01*
X576087Y-325875D01*
X575617Y-325245D01*
X575304Y-324510D01*
X575147Y-323670D01*
Y-322830D01*
X575304Y-321990D01*
X575617Y-321255D01*
X576087Y-320625D01*
X576635Y-320205D01*
X577262Y-320100D01*
X577889Y-320205D01*
X578437Y-320625D01*
X578907Y-321255D01*
X579220Y-321990D01*
X579377Y-322830D01*
Y-323670D01*
X579220Y-324510D01*
X578907Y-325245D01*
X578437Y-325875D01*
X577889Y-326295D01*
X577262Y-326400D01*
G01X589862D02*
Y-323565D01*
X588295Y-320100D01*
G01X591429D02*
X589862Y-323565D01*
G01X594439Y-320100D02*
Y-324615D01*
X594752Y-325560D01*
X595379Y-326190D01*
X596162Y-326400D01*
X596945Y-326190D01*
X597572Y-325560D01*
X597885Y-324615D01*
Y-320100D01*
G01X600504Y-326400D02*
X602462Y-320100D01*
X604420Y-326400D01*
G01X603715Y-324195D02*
X601209D01*
G01X606960Y-326400D02*
Y-320100D01*
X610564Y-326400D01*
Y-320100D01*
G01X455760Y-316400D02*
Y-310100D01*
X459364Y-316400D01*
Y-310100D01*
G01X463862Y-316400D02*
X463235Y-316295D01*
X462687Y-315875D01*
X462217Y-315245D01*
X461904Y-314510D01*
X461747Y-313670D01*
Y-312830D01*
X461904Y-311990D01*
X462217Y-311255D01*
X462687Y-310625D01*
X463235Y-310205D01*
X463862Y-310100D01*
X464489Y-310205D01*
X465037Y-310625D01*
X465507Y-311255D01*
X465820Y-311990D01*
X465977Y-312830D01*
Y-313670D01*
X465820Y-314510D01*
X465507Y-315245D01*
X465037Y-315875D01*
X464489Y-316295D01*
X463862Y-316400D01*
G01X470162Y-316610D02*
X470005Y-316505D01*
Y-316295D01*
X470162Y-316190D01*
X470319Y-316295D01*
Y-316505D01*
X470162Y-316610D01*
G01X476462Y-316400D02*
Y-310100D01*
X475522Y-311360D01*
G01Y-316400D02*
X477402D01*
G01X482762D02*
X483310Y-316295D01*
X483937Y-315980D01*
X484329Y-315455D01*
X484485Y-314720D01*
X484329Y-313985D01*
X483859Y-313355D01*
X483154Y-313040D01*
X482370D01*
X481900Y-312830D01*
X481509Y-312305D01*
X481352Y-311570D01*
X481587Y-310835D01*
X482135Y-310310D01*
X482762Y-310100D01*
X483389Y-310310D01*
X483937Y-310835D01*
X484172Y-311570D01*
X484015Y-312305D01*
X483624Y-312830D01*
X483154Y-313040D01*
X482370D01*
X481665Y-313355D01*
X481195Y-313985D01*
X481039Y-314720D01*
X481195Y-315455D01*
X481587Y-315980D01*
X482214Y-316295D01*
X482762Y-316400D01*
G01X489062D02*
X489610Y-316295D01*
X490237Y-315980D01*
X490629Y-315455D01*
X490785Y-314720D01*
X490629Y-313985D01*
X490159Y-313355D01*
X489454Y-313040D01*
X488670D01*
X488200Y-312830D01*
X487809Y-312305D01*
X487652Y-311570D01*
X487887Y-310835D01*
X488435Y-310310D01*
X489062Y-310100D01*
X489689Y-310310D01*
X490237Y-310835D01*
X490472Y-311570D01*
X490315Y-312305D01*
X489924Y-312830D01*
X489454Y-313040D01*
X488670D01*
X487965Y-313355D01*
X487495Y-313985D01*
X487339Y-314720D01*
X487495Y-315455D01*
X487887Y-315980D01*
X488514Y-316295D01*
X489062Y-316400D01*
G01X495205Y-317555D02*
X495519Y-316190D01*
G01X499312Y-310100D02*
X500409Y-316400D01*
X501662Y-310100D01*
X502915Y-316400D01*
X504012Y-310100D01*
G01X509529Y-316400D02*
X506395D01*
Y-310100D01*
X509529D01*
G01X508275Y-313145D02*
X506395D01*
G01X512460Y-316400D02*
Y-310100D01*
X516064Y-316400D01*
Y-310100D01*
G01X525217Y-316400D02*
Y-310100D01*
G01X528507D02*
Y-316400D01*
G01Y-313250D02*
X525217D01*
G01X530812Y-310100D02*
X531909Y-316400D01*
X533162Y-310100D01*
X534415Y-316400D01*
X535512Y-310100D01*
G01X537504Y-316400D02*
X539462Y-310100D01*
X541420Y-316400D01*
G01X540715Y-314195D02*
X538209D01*
G01X550574Y-311150D02*
X551044Y-310520D01*
X551592Y-310205D01*
X552219Y-310100D01*
X553002Y-310310D01*
X553550Y-310835D01*
X553707Y-311465D01*
X553629Y-312095D01*
X553315Y-312620D01*
X551749Y-313670D01*
X551044Y-314405D01*
X550574Y-315455D01*
X550417Y-316400D01*
X553707D01*
G01X556560D02*
Y-310100D01*
X560164Y-316400D01*
Y-310100D01*
G01X562939Y-316400D02*
Y-310100D01*
X564505D01*
X565132Y-310415D01*
X565602Y-310835D01*
X565994Y-311465D01*
X566307Y-312200D01*
X566385Y-313250D01*
X566307Y-314300D01*
X565994Y-315035D01*
X565602Y-315665D01*
X565132Y-316085D01*
X564505Y-316400D01*
X562939D01*
G01X575695D02*
Y-310100D01*
X577654D01*
X578280Y-310415D01*
X578672Y-310835D01*
X578829Y-311675D01*
X578672Y-312515D01*
X578202Y-313040D01*
X577654Y-313355D01*
X575695D01*
G01X577654D02*
X578829Y-316400D01*
G01X581839D02*
Y-310100D01*
X583405D01*
X584032Y-310415D01*
X584502Y-310835D01*
X584894Y-311465D01*
X585207Y-312200D01*
X585285Y-313250D01*
X585207Y-314300D01*
X584894Y-315035D01*
X584502Y-315665D01*
X584032Y-316085D01*
X583405Y-316400D01*
X581839D01*
G01X589862Y-316610D02*
X589705Y-316505D01*
Y-316295D01*
X589862Y-316190D01*
X590019Y-316295D01*
Y-316505D01*
X589862Y-316610D01*
G01X468859Y115666D02*
X470732Y119413D01*
X470463Y120218D01*
X469926Y120486D01*
X469694Y120602D01*
X469510Y120787D01*
X466750D01*
X464200Y118237D01*
Y111363D01*
X483800Y91763D01*
Y60063D01*
X487158Y56705D01*
Y16879D01*
X485621Y15342D01*
X483000D01*
X482402Y14744D01*
Y13386D01*
G01Y18898D02*
Y17540D01*
X483000Y16942D01*
X484958D01*
X485558Y17542D01*
Y56042D01*
X482200Y59400D01*
Y91100D01*
X462600Y110700D01*
Y118900D01*
X466087Y122387D01*
X470173D01*
X470642Y121918D01*
X471179Y121650D01*
X471984Y121917D01*
X473859Y125666D01*
G01X479862Y-303700D02*
X477342Y-303283D01*
X475137Y-301617D01*
X473247Y-299117D01*
X471987Y-296200D01*
X471357Y-292867D01*
Y-289533D01*
X471987Y-286200D01*
X473247Y-283283D01*
X475137Y-280784D01*
X477342Y-279117D01*
X479862Y-278700D01*
X482382Y-279117D01*
X484587Y-280784D01*
X486477Y-283283D01*
X487737Y-286200D01*
X488367Y-289533D01*
Y-292867D01*
X487737Y-296200D01*
X486477Y-299117D01*
X484587Y-301617D01*
X482382Y-303283D01*
X479862Y-303700D01*
G01X482382Y-297033D02*
X486162Y-303700D01*
G01X499707Y-287034D02*
Y-298700D01*
X500967Y-301617D01*
X502857Y-303283D01*
X505062Y-303700D01*
X507267Y-303283D01*
X509157Y-301617D01*
X510417Y-298700D01*
G01Y-303700D02*
Y-287034D01*
G01X535932Y-303700D02*
Y-287034D01*
G01Y-289950D02*
X534672Y-288284D01*
X532782Y-287450D01*
X530577Y-287034D01*
X528372Y-287867D01*
X526482Y-289533D01*
X525222Y-292034D01*
X524592Y-295367D01*
X525222Y-298700D01*
X526482Y-301201D01*
X528372Y-302867D01*
X530577Y-303700D01*
X532782Y-303283D01*
X534672Y-302034D01*
X535932Y-300367D01*
G01X550107Y-303700D02*
Y-287034D01*
G01Y-291200D02*
X551367Y-289117D01*
X553257Y-287450D01*
X555777Y-287034D01*
X557982Y-287450D01*
X559872Y-289117D01*
X560817Y-292034D01*
Y-303700D01*
G01X580662Y-278700D02*
Y-303700D01*
G01X576252Y-287034D02*
X585072D01*
G01X611532Y-303700D02*
Y-287034D01*
G01Y-289950D02*
X610272Y-288284D01*
X608382Y-287450D01*
X606177Y-287034D01*
X603972Y-287867D01*
X602082Y-289533D01*
X600822Y-292034D01*
X600192Y-295367D01*
X600822Y-298700D01*
X602082Y-301201D01*
X603972Y-302867D01*
X606177Y-303700D01*
X608382Y-303283D01*
X610272Y-302034D01*
X611532Y-300367D01*
G01X478859Y141650D02*
X483050D01*
X487400Y137300D01*
X492037D01*
X497950Y131387D01*
Y123213D01*
X493500Y118763D01*
Y108837D01*
X500000Y102337D01*
Y85837D01*
X501700Y84137D01*
Y34471D01*
X500706Y33477D01*
X498700D01*
X498150Y34027D01*
Y35433D01*
G01X506024Y8268D02*
Y9748D01*
X506500Y10224D01*
X512687D01*
X516700Y14237D01*
Y78800D01*
X511600Y83900D01*
Y102200D01*
X506100Y107700D01*
Y116900D01*
X509200Y120000D01*
Y140418D01*
X502790Y146828D01*
X502253Y147096D01*
X501984Y147901D01*
X503859Y151650D01*
G01X506024Y13780D02*
Y12376D01*
X506576Y11824D01*
X512024D01*
X515100Y14900D01*
Y62628D01*
X514400Y63328D01*
Y65128D01*
X515100Y65828D01*
Y67628D01*
X514400Y68328D01*
Y70128D01*
X515100Y70828D01*
Y72628D01*
X514400Y73328D01*
Y75128D01*
X515100Y75828D01*
Y78137D01*
X510000Y83237D01*
Y101537D01*
X504500Y107037D01*
Y117563D01*
X507600Y120663D01*
Y139755D01*
X501842Y145512D01*
X501537Y145664D01*
X500732Y145397D01*
X498859Y141650D01*
G01X493859Y151650D02*
Y137741D01*
X499550Y132050D01*
Y122550D01*
X495100Y118100D01*
Y109500D01*
X501600Y103000D01*
Y86500D01*
X503300Y84800D01*
Y33808D01*
X501369Y31877D01*
X498700D01*
X498150Y31327D01*
Y29922D01*
G01X651212Y-283400D02*
Y-291400D01*
X655212D01*
G01X663012D02*
Y-286067D01*
G01Y-287000D02*
X662612Y-286467D01*
X662012Y-286200D01*
X661312Y-286067D01*
X660612Y-286333D01*
X660012Y-286867D01*
X659612Y-287667D01*
X659412Y-288733D01*
X659612Y-289800D01*
X660012Y-290600D01*
X660612Y-291133D01*
X661312Y-291400D01*
X662012Y-291267D01*
X662612Y-290867D01*
X663012Y-290334D01*
G01X667112Y-293800D02*
X667712Y-294067D01*
X668512Y-293800D01*
X669012Y-293267D01*
X669412Y-292600D01*
X670012Y-290467D01*
X671312Y-286067D01*
G01X668112D02*
X670012Y-290467D01*
G01X675712Y-287800D02*
X678912D01*
X678612Y-286867D01*
X678112Y-286333D01*
X677412Y-286067D01*
X676712Y-286200D01*
X676112Y-286600D01*
X675712Y-287533D01*
X675512Y-288334D01*
Y-289133D01*
X675712Y-289933D01*
X676212Y-290733D01*
X676812Y-291267D01*
X677512Y-291400D01*
X678212Y-291133D01*
X678912Y-290334D01*
G01X683812Y-291400D02*
Y-286067D01*
G01Y-287133D02*
X684312Y-286600D01*
X684812Y-286200D01*
X685512Y-286067D01*
X686012Y-286200D01*
X686612Y-286600D01*
G01X649173Y29922D02*
X647218Y31877D01*
X640851D01*
G02X638305Y32931I-1J3599D01*
G01X636255Y34982D01*
G02X635200Y37528I2545J2546D01*
G01Y66572D01*
G02X636254Y69118I3599J1D01*
G01X637814Y70678D01*
Y71613D01*
X639087Y72886D01*
X640023D01*
X641296Y74159D01*
Y75095D01*
X642569Y76368D01*
X643505D01*
X644778Y77641D01*
Y78577D01*
X646051Y79850D01*
X646987D01*
X648260Y81123D01*
Y82059D01*
X649533Y83332D01*
X650469D01*
X651742Y84605D01*
Y85541D01*
X653015Y86814D01*
X653951D01*
X657583Y90446D01*
G03X657700Y90728I-281J282D01*
G01Y93172D01*
G03X657583Y93454I-398J0D01*
G01X657354Y93683D01*
G03X657072Y93800I-282J-281D01*
G01X656100D01*
X654400Y92100D01*
G01X649173Y51969D02*
Y50773D01*
X648413Y50013D01*
X645444D01*
G02X644493Y50407I0J1345D01*
G02X644100Y51356I949J949D01*
G01Y64209D01*
G02X644686Y65623I1999J0D01*
G01X645502Y66439D01*
X646537D01*
X647811Y67713D01*
Y68229D01*
X647809Y68746D01*
X649084Y70021D01*
X650119D01*
X651393Y71295D01*
Y71811D01*
X651391Y72328D01*
X652666Y73603D01*
X653701D01*
X654975Y74877D01*
Y75393D01*
X654973Y75910D01*
X659284Y80221D01*
X660319D01*
X661594Y81496D01*
X661592Y82013D01*
Y82529D01*
X662866Y83803D01*
X663901D01*
X665176Y85078D01*
X665174Y85595D01*
Y86111D01*
X666045Y86982D01*
G03X667100Y89528I-2545J2546D01*
G01Y99972D01*
G03X666514Y101386I-1999J0D01*
G01X656086Y111814D01*
G02X655500Y113228I1413J1414D01*
G01Y119072D01*
G02X656086Y120486I1999J0D01*
G01X664914Y129314D01*
G02X666328Y129900I1414J-1413D01*
G01X671872D01*
G02X672154Y129783I0J-398D01*
G01X672646Y129291D01*
G02X672763Y129009I-281J-282D01*
G01Y127630D01*
X671063Y125930D01*
G01X649173Y46457D02*
Y47727D01*
X648487Y48413D01*
X645444D01*
G02X643361Y49275I-1J2945D01*
G02X642500Y51356I2082J2080D01*
G01Y64209D01*
G02X643554Y66755I3599J1D01*
G01X664914Y88114D01*
G03X665500Y89528I-1413J1414D01*
G01Y99972D01*
G03X665383Y100254I-398J0D01*
G01X654955Y110682D01*
G02X653900Y113228I2545J2546D01*
G01Y119072D01*
G02X654954Y121618I3599J1D01*
G01X663782Y130445D01*
G02X666328Y131500I2546J-2545D01*
G01X671872D01*
G02X673286Y130914I0J-1999D01*
G01X673777Y130423D01*
G02X674363Y129009I-1413J-1414D01*
G01Y127630D01*
X676063Y125930D01*
G01X649173Y35433D02*
X647217Y33477D01*
X640851D01*
G02X639437Y34063I0J1999D01*
G01X637386Y36114D01*
G02X636800Y37528I1413J1414D01*
G01Y66572D01*
G02X637386Y67986I1999J0D01*
G01X658714Y89314D01*
G03X659300Y90728I-1413J1414D01*
G01Y93172D01*
G03X658714Y94586I-1999J0D01*
G01X658486Y94814D01*
G03X657072Y95400I-1414J-1413D01*
G01X656100D01*
X654400Y97100D01*
G01X673512Y-333400D02*
X675912D01*
G01X674712D02*
Y-341400D01*
G01X673512D02*
X675912D01*
G01X681312D02*
Y-336067D01*
G01Y-337133D02*
X681812Y-336600D01*
X682312Y-336200D01*
X683012Y-336067D01*
X683512Y-336200D01*
X684112Y-336600D01*
G01X689212Y-337800D02*
X692412D01*
X692112Y-336867D01*
X691612Y-336333D01*
X690912Y-336067D01*
X690212Y-336200D01*
X689612Y-336600D01*
X689212Y-337533D01*
X689012Y-338334D01*
Y-339133D01*
X689212Y-339933D01*
X689712Y-340733D01*
X690312Y-341267D01*
X691012Y-341400D01*
X691712Y-341133D01*
X692412Y-340334D01*
G01X697012Y-341400D02*
Y-336067D01*
G01Y-337400D02*
X697412Y-336733D01*
X698012Y-336200D01*
X698812Y-336067D01*
X699512Y-336200D01*
X700112Y-336733D01*
X700412Y-337667D01*
Y-341400D01*
G01X705212Y-337800D02*
X708412D01*
X708112Y-336867D01*
X707612Y-336333D01*
X706912Y-336067D01*
X706212Y-336200D01*
X705612Y-336600D01*
X705212Y-337533D01*
X705012Y-338334D01*
Y-339133D01*
X705212Y-339933D01*
X705712Y-340733D01*
X706312Y-341267D01*
X707012Y-341400D01*
X707712Y-341133D01*
X708412Y-340334D01*
G01X672795Y30315D02*
Y28967D01*
X672187Y28359D01*
X670598D01*
G02X669945Y28630I0J922D01*
G01X669851Y28724D01*
G02X669674Y29149I422J425D01*
G01Y52200D01*
X670170Y55177D01*
X671789Y59089D01*
X680514Y67814D01*
G02X681928Y68400I1414J-1413D01*
G01X683880D01*
G03X684645Y68552I0J2001D01*
G01X686933Y69500D01*
G03X687278Y69684I-764J1848D01*
G01X691531Y72522D01*
G03X691835Y72772I-1112J1662D01*
G01X701239Y82176D01*
X702177D01*
X703449Y83448D01*
Y84386D01*
X704721Y85658D01*
X705659D01*
X706931Y86930D01*
Y87868D01*
X717445Y98382D01*
G03X718500Y100928I-2545J2546D01*
G01Y103672D01*
G02X719086Y105086I1999J0D01*
G01X723014Y109014D01*
G02X724428Y109600I1414J-1413D01*
G01X725972D01*
G03X727386Y110186I0J1999D01*
G01X728024Y110824D01*
G03X728610Y112238I-1413J1414D01*
G01Y113690D01*
X730310Y115390D01*
G01X725310D02*
X727010Y113690D01*
Y112238D01*
G02X726893Y111956I-398J0D01*
G01X726254Y111317D01*
G02X725972Y111200I-282J281D01*
G01X724428D01*
G03X721882Y110145I0J-3600D01*
G01X717954Y106218D01*
G03X716900Y103672I2545J-2545D01*
G01Y100928D01*
G02X716314Y99514I-1999J0D01*
G01X690702Y73902D01*
G02X690641Y73853I-279J285D01*
G01X686390Y71016D01*
G02X686321Y70979I-222J332D01*
G01X684033Y70031D01*
G02X683880Y70000I-155J370D01*
G01X681928D01*
G03X679382Y68945I0J-3600D01*
G01X670432Y59995D01*
X668621Y55620D01*
X668074Y52333D01*
Y29149D01*
G03X668721Y27591I2199J0D01*
G01X668813Y27499D01*
G03X670598Y26759I1785J1783D01*
G01X672274D01*
X672795Y26238D01*
Y24803D01*
G01X657047Y8268D02*
Y9753D01*
X656576Y10224D01*
X654890D01*
G02X653053Y10984I0J2600D01*
G02X652291Y12823I1838J1839D01*
G01Y60963D01*
G02X652877Y62377I1999J0D01*
G01X660766Y70266D01*
G03Y71444I-589J589D01*
G01X659310Y72900D01*
G01X657047Y13780D02*
Y12247D01*
X656624Y11824D01*
X654890D01*
G02X654184Y12116I0J999D01*
G02X653891Y12823I706J707D01*
G01Y56433D01*
X654600Y57141D01*
Y58941D01*
X653891Y59649D01*
Y60963D01*
G02X654008Y61245I398J0D01*
G01X661898Y69134D01*
G03X662610Y70855I-1721J1720D01*
G03Y71200I-2433J172D01*
G01X662586Y71196D01*
X664310Y72900D01*
G01X689961Y122030D02*
X691661Y123730D01*
Y125011D01*
G03X691544Y125293I-398J0D01*
G01X690854Y125983D01*
G03X690572Y126100I-282J-281D01*
G01X689327D01*
G03X689045Y125983I1J-400D01*
G01X688125Y125062D01*
X686768Y123706D01*
X684440Y121375D01*
X684424Y121360D01*
G03X684300Y121071I275J-289D01*
G01Y117514D01*
X685000Y116814D01*
Y115214D01*
X684300Y114514D01*
Y112714D01*
X685000Y112014D01*
Y110414D01*
X684300Y109714D01*
Y107408D01*
X684900Y106808D01*
Y105008D01*
X684300Y104408D01*
Y102928D01*
G03X684886Y101514I1999J0D01*
G01X685214Y101186D01*
G02X685800Y99772I-1413J-1414D01*
G01Y92228D01*
G02X685214Y90814I-1999J0D01*
G01X684442Y90042D01*
Y89142D01*
X683169Y87869D01*
X682269D01*
X680996Y86596D01*
Y85696D01*
X679723Y84423D01*
X678823D01*
X677550Y83150D01*
Y82250D01*
X676277Y80977D01*
X675377D01*
X672686Y78286D01*
G03X672100Y76872I1413J-1414D01*
G01Y69728D01*
G02X671514Y68314I-1999J0D01*
G01X662186Y58986D01*
G03X661600Y57572I1413J-1414D01*
G01Y51527D01*
G03X662043Y50456I1514J-1D01*
G01X662044Y50455D01*
G03X663113Y50013I1069J1072D01*
G01X664313D01*
X664921Y50621D01*
Y51969D01*
G01X694961Y122030D02*
X693261Y123730D01*
Y125011D01*
G03X692675Y126425I-1999J0D01*
G01X691986Y127114D01*
G03X690572Y127700I-1414J-1413D01*
G01X689328D01*
G03X687913Y127114I-1J-2000D01*
G01X685636Y124837D01*
X683323Y122521D01*
G03X682700Y121071I1376J-1450D01*
G01Y102928D01*
G03X683754Y100382I3599J-1D01*
G01X684083Y100054D01*
G02X684200Y99772I-281J-282D01*
G01Y92228D01*
G02X684083Y91946I-398J0D01*
G01X671555Y79418D01*
G03X670500Y76872I2545J-2546D01*
G01Y69728D01*
G02X670383Y69446I-398J0D01*
G01X661055Y60118D01*
G03X660000Y57572I2545J-2546D01*
G01Y51528D01*
G03X660911Y49325I3114J-2D01*
G01X660913Y49323D01*
G03X663113Y48413I2200J2204D01*
G01X664187D01*
X664921Y47679D01*
Y46457D01*
G01X683512Y-308400D02*
X685912D01*
G01X684712D02*
Y-316400D01*
G01X683512D02*
X685912D01*
G01X690412D02*
Y-308400D01*
X695012Y-316400D01*
Y-308400D01*
G01X698812Y-309733D02*
X699412Y-308933D01*
X700112Y-308533D01*
X700912Y-308400D01*
X701912Y-308667D01*
X702612Y-309333D01*
X702812Y-310133D01*
X702712Y-310934D01*
X702312Y-311600D01*
X700312Y-312933D01*
X699412Y-313867D01*
X698812Y-315200D01*
X698612Y-316400D01*
X702812D01*
G01X752480Y92830D02*
X750780Y91130D01*
Y88708D01*
G02X749726Y86162I-3599J-1D01*
G01X719618Y56055D01*
G02X717072Y55000I-2546J2545D01*
G01X715511D01*
X714911Y54400D01*
X713111D01*
X712511Y55000D01*
X710711D01*
X710111Y54400D01*
X708311D01*
X707711Y55000D01*
X705911D01*
X705311Y54400D01*
X703511D01*
X702911Y55000D01*
X701111D01*
X700511Y54400D01*
X698711D01*
X698111Y55000D01*
X696311D01*
X695711Y54400D01*
X693911D01*
X693311Y55000D01*
X688128D01*
G03X686714Y54414I0J-1999D01*
G01X686011Y53711D01*
G03X685425Y52297I1413J-1414D01*
G01Y34242D01*
G02X684733Y32569I-2366J-1D01*
G02X683060Y31877I-1672J1674D01*
G01X681474D01*
X680669Y31072D01*
Y29922D01*
G01X778200Y92130D02*
X779900Y93830D01*
X781154D01*
G02X782035Y93465I0J-1246D01*
G02X782400Y92585I-881J-881D01*
G01Y90319D01*
X782399D01*
G02X782369Y90166I-399J-1D01*
G01X780127Y84756D01*
X780126Y84755D01*
G02X780090Y84686I-370J149D01*
G01X758961Y53072D01*
X758940Y53041D01*
X730147Y24248D01*
G02X729966Y24100I-842J845D01*
G02X729865Y24039I-663J984D01*
G02X729762Y23990I-561J1046D01*
G01X700830Y11953D01*
G02X700062Y11800I-767J1847D01*
G01X690523D01*
X688543Y13780D01*
G01Y8268D02*
X690475Y10200D01*
X700062D01*
G03X701445Y10475I3J3600D01*
G01X730377Y22512D01*
G03X730624Y22630I-1077J2571D01*
G03X730858Y22771I-1320J2455D01*
G03X731279Y23117I-1555J2321D01*
G01X736493Y28331D01*
X737431D01*
X738703Y29603D01*
Y30541D01*
X739975Y31813D01*
X740913D01*
X742185Y33085D01*
Y34023D01*
X743457Y35295D01*
X744395D01*
X745667Y36567D01*
Y37505D01*
X746939Y38777D01*
X747877D01*
X749149Y40049D01*
Y40987D01*
X750421Y42259D01*
X751359D01*
X752631Y43531D01*
Y44469D01*
X753903Y45741D01*
X754841D01*
X756113Y47013D01*
Y47951D01*
X760179Y52017D01*
X760289Y52178D01*
X781420Y83795D01*
Y83796D01*
X781422Y83799D01*
G03X781606Y84145I-1665J1108D01*
G01X783848Y89554D01*
G03X784000Y90320I-1848J765D01*
G01Y92584D01*
G03X783167Y94597I-2846J1D01*
G03X781154Y95430I-2012J-2013D01*
G01X779900D01*
X778200Y97130D01*
G01X747480Y92830D02*
X749180Y91130D01*
Y88708D01*
G02X748594Y87294I-1999J0D01*
G01X718486Y57186D01*
G02X717072Y56600I-1414J1413D01*
G01X688128D01*
G03X685582Y55546I-1J-3599D01*
G01X684880Y54843D01*
G03X683825Y52297I2545J-2546D01*
G01Y34241D01*
G02X683601Y33701I-765J1D01*
G02X683060Y33477I-541J541D01*
G01X681574D01*
X680669Y34382D01*
Y35433D01*
G01X761929Y72900D02*
X760229Y71200D01*
Y69357D01*
G02X759175Y66811I-3599J-1D01*
G01X736713Y44350D01*
G02X734167Y43295I-2546J2545D01*
G01X717999D01*
X717305Y42600D01*
X715505D01*
X714811Y43295D01*
X713011D01*
X712317Y42600D01*
X710517D01*
X709823Y43295D01*
X708023D01*
X707329Y42600D01*
X705529D01*
X704835Y43295D01*
X690499D01*
X688543Y41339D01*
G01X756929Y72900D02*
X758629Y71200D01*
Y69357D01*
G02X758043Y67943I-1999J0D01*
G01X735581Y45481D01*
G02X734167Y44895I-1414J1413D01*
G01X690499D01*
X688543Y46851D01*
G01X760410Y124730D02*
X758710Y126430D01*
Y127362D01*
G03X758124Y128776I-1999J0D01*
G01X757786Y129114D01*
G03X756372Y129700I-1414J-1413D01*
G01X754484D01*
G03X753104Y129427I-5J-3601D01*
G01X745984Y126475D01*
G03X745343Y126130I1377J-3326D01*
G01X743221Y124692D01*
G03X742693Y124257I2015J-2984D01*
G01X741008Y122572D01*
G03X740558Y122023I2546J-2546D01*
G01X738215Y118507D01*
G03X737884Y117888I2994J-1999D01*
G01X737565Y117118D01*
G03X737400Y116284I2017J-832D01*
G01Y115917D01*
G02X737369Y115764I-400J1D01*
G01X732353Y103659D01*
G02X732266Y103529I-370J153D01*
G01X710420Y81683D01*
G02X710378Y81645I-423J425D01*
G01X700425Y73422D01*
G03X700412Y73411I382J-464D01*
G01X700399Y73400D01*
X700400D01*
X692300Y66300D01*
X682255Y61718D01*
X676131Y55594D01*
X675748Y54667D01*
Y51445D01*
G03X676637Y49300I3032J0D01*
G03X678780Y48413I2143J2145D01*
G01X679887D01*
X680669Y47631D01*
Y46457D01*
G01X755410Y124730D02*
X757110Y126430D01*
Y127362D01*
G03X756993Y127644I-398J0D01*
G01X756654Y127983D01*
G03X756372Y128100I-282J-281D01*
G01X754483D01*
G03X753717Y127948I-1J-2000D01*
G01X746597Y124997D01*
G03X746241Y124805I766J-1847D01*
G01X744118Y123367D01*
G03X743825Y123125I1121J-1656D01*
G01X742140Y121440D01*
G03X741890Y121135I1414J-1414D01*
G01X739546Y117619D01*
G03X739362Y117275I1663J-1111D01*
G01X739044Y116507D01*
G03X739000Y116284I538J-222D01*
G01Y115918D01*
G02X738848Y115152I-2000J-1D01*
G01X733831Y103046D01*
G02X733398Y102398I-1848J766D01*
G01X731931Y100931D01*
Y100033D01*
X730658Y98760D01*
X729760D01*
X728487Y97487D01*
Y96589D01*
X727214Y95316D01*
X726316D01*
X725043Y94043D01*
Y93145D01*
X723770Y91872D01*
X722872D01*
X721599Y90599D01*
Y89701D01*
X720326Y88428D01*
X719428D01*
X718155Y87155D01*
Y86257D01*
X716882Y84984D01*
X715984D01*
X714711Y83711D01*
Y82813D01*
X713438Y81540D01*
X712540D01*
X711478Y80478D01*
X701455Y72197D01*
X693178Y64941D01*
X683182Y60382D01*
X677488Y54688D01*
X677348Y54349D01*
Y51445D01*
G03X677768Y50432I1432J0D01*
G03X678780Y50013I1012J1013D01*
G01X679913D01*
X680669Y50769D01*
Y51969D01*
G01X702812Y-288067D02*
X703512Y-287133D01*
X704112Y-286600D01*
X704912Y-286333D01*
X705612Y-286600D01*
X706112Y-287133D01*
X706512Y-287933D01*
X706612Y-288867D01*
X706512Y-289667D01*
X706112Y-290467D01*
X705512Y-291133D01*
X704812Y-291400D01*
X704012Y-291133D01*
X703312Y-290334D01*
X702912Y-289133D01*
X702812Y-287800D01*
X703012Y-286067D01*
X703312Y-285133D01*
X703812Y-284200D01*
X704512Y-283533D01*
X705212Y-283400D01*
X705912Y-283667D01*
X706412Y-284333D01*
G01X777812Y-334733D02*
X778412Y-333933D01*
X779112Y-333533D01*
X779912Y-333400D01*
X780912Y-333667D01*
X781612Y-334333D01*
X781812Y-335133D01*
X781712Y-335934D01*
X781312Y-336600D01*
X779312Y-337933D01*
X778412Y-338867D01*
X777812Y-340200D01*
X777612Y-341400D01*
X781812D01*
G01X787712Y-333400D02*
X786912Y-333667D01*
X786312Y-334333D01*
X785912Y-335133D01*
X785612Y-336200D01*
X785512Y-337400D01*
X785612Y-338600D01*
X785912Y-339667D01*
X786312Y-340467D01*
X786912Y-341133D01*
X787712Y-341400D01*
X788512Y-341133D01*
X789112Y-340467D01*
X789512Y-339667D01*
X789812Y-338600D01*
X789912Y-337400D01*
X789812Y-336200D01*
X789512Y-335133D01*
X789112Y-334333D01*
X788512Y-333667D01*
X787712Y-333400D01*
G01X795712Y-341400D02*
Y-333400D01*
X794512Y-335000D01*
G01Y-341400D02*
X796912D01*
G01X801812Y-334733D02*
X802412Y-333933D01*
X803112Y-333533D01*
X803912Y-333400D01*
X804912Y-333667D01*
X805612Y-334333D01*
X805812Y-335133D01*
X805712Y-335934D01*
X805312Y-336600D01*
X803312Y-337933D01*
X802412Y-338867D01*
X801812Y-340200D01*
X801612Y-341400D01*
X805812D01*
G01X809912Y-341667D02*
X813512Y-333400D01*
G01X819712Y-341400D02*
Y-333400D01*
X818512Y-335000D01*
G01Y-341400D02*
X820912D01*
G01X827712Y-333400D02*
X826912Y-333667D01*
X826312Y-334333D01*
X825912Y-335133D01*
X825612Y-336200D01*
X825512Y-337400D01*
X825612Y-338600D01*
X825912Y-339667D01*
X826312Y-340467D01*
X826912Y-341133D01*
X827712Y-341400D01*
X828512Y-341133D01*
X829112Y-340467D01*
X829512Y-339667D01*
X829812Y-338600D01*
X829912Y-337400D01*
X829812Y-336200D01*
X829512Y-335133D01*
X829112Y-334333D01*
X828512Y-333667D01*
X827712Y-333400D01*
G01X833912Y-341667D02*
X837512Y-333400D01*
G01X841512Y-339800D02*
X842112Y-340733D01*
X842912Y-341267D01*
X843812Y-341400D01*
X844612Y-341267D01*
X845412Y-340600D01*
X845912Y-339800D01*
X846012Y-339000D01*
X845812Y-338067D01*
X845112Y-337400D01*
X844412Y-337133D01*
X843512D01*
G01X844412D02*
X845012Y-336733D01*
X845512Y-336067D01*
X845712Y-335267D01*
X845512Y-334467D01*
X845012Y-333800D01*
X844112Y-333400D01*
X843212Y-333533D01*
X842312Y-334067D01*
G01X851712Y-341400D02*
Y-333400D01*
X850512Y-335000D01*
G01Y-341400D02*
X852912D01*
G01X777512Y-316400D02*
Y-308400D01*
X779512D01*
X780312Y-308800D01*
X780912Y-309333D01*
X781412Y-310133D01*
X781812Y-311067D01*
X781912Y-312400D01*
X781812Y-313733D01*
X781412Y-314667D01*
X780912Y-315467D01*
X780312Y-316000D01*
X779512Y-316400D01*
X777512D01*
G01X785212D02*
X787712Y-308400D01*
X790212Y-316400D01*
G01X789312Y-313600D02*
X786112D01*
G01X795712Y-308400D02*
X794912Y-308667D01*
X794312Y-309333D01*
X793912Y-310133D01*
X793612Y-311200D01*
X793512Y-312400D01*
X793612Y-313600D01*
X793912Y-314667D01*
X794312Y-315467D01*
X794912Y-316133D01*
X795712Y-316400D01*
X796512Y-316133D01*
X797112Y-315467D01*
X797512Y-314667D01*
X797812Y-313600D01*
X797912Y-312400D01*
X797812Y-311200D01*
X797512Y-310133D01*
X797112Y-309333D01*
X796512Y-308667D01*
X795712Y-308400D01*
G01X803712D02*
Y-316400D01*
G01X801412Y-308400D02*
X806012D01*
G01X809812Y-313067D02*
X810512Y-312133D01*
X811112Y-311600D01*
X811912Y-311333D01*
X812612Y-311600D01*
X813112Y-312133D01*
X813512Y-312933D01*
X813612Y-313867D01*
X813512Y-314667D01*
X813112Y-315467D01*
X812512Y-316133D01*
X811812Y-316400D01*
X811012Y-316133D01*
X810312Y-315334D01*
X809912Y-314133D01*
X809812Y-312800D01*
X810012Y-311067D01*
X810312Y-310133D01*
X810812Y-309200D01*
X811512Y-308533D01*
X812212Y-308400D01*
X812912Y-308667D01*
X813412Y-309333D01*
G01X817112Y-316400D02*
Y-308400D01*
X819712Y-315067D01*
X822312Y-308400D01*
Y-316400D01*
G01X827712Y-308400D02*
Y-316400D01*
G01X825412Y-308400D02*
X830012D01*
G01X833612Y-316400D02*
Y-308400D01*
G01X837812D02*
Y-316400D01*
G01Y-312400D02*
X833612D01*
G01X843712Y-316400D02*
X844412Y-316267D01*
X845212Y-315867D01*
X845712Y-315200D01*
X845912Y-314267D01*
X845712Y-313334D01*
X845112Y-312533D01*
X844212Y-312133D01*
X843212D01*
X842612Y-311867D01*
X842112Y-311200D01*
X841912Y-310267D01*
X842212Y-309333D01*
X842912Y-308667D01*
X843712Y-308400D01*
X844512Y-308667D01*
X845212Y-309333D01*
X845512Y-310267D01*
X845312Y-311200D01*
X844812Y-311867D01*
X844212Y-312133D01*
X843212D01*
X842312Y-312533D01*
X841712Y-313334D01*
X841512Y-314267D01*
X841712Y-315200D01*
X842212Y-315867D01*
X843012Y-316267D01*
X843712Y-316400D01*
G01X853912Y-309067D02*
X853312Y-308667D01*
X852612Y-308400D01*
X851812D01*
X850912Y-308800D01*
X850212Y-309467D01*
X849712Y-310267D01*
X849312Y-311600D01*
X849212Y-312800D01*
X849412Y-314000D01*
X849712Y-314800D01*
X850312Y-315600D01*
X851012Y-316133D01*
X851712Y-316400D01*
X852412D01*
X853112Y-316133D01*
X853712Y-315733D01*
X854212Y-315200D01*
G01X859712Y-308400D02*
X858912Y-308667D01*
X858312Y-309333D01*
X857912Y-310133D01*
X857612Y-311200D01*
X857512Y-312400D01*
X857612Y-313600D01*
X857912Y-314667D01*
X858312Y-315467D01*
X858912Y-316133D01*
X859712Y-316400D01*
X860512Y-316133D01*
X861112Y-315467D01*
X861512Y-314667D01*
X861812Y-313600D01*
X861912Y-312400D01*
X861812Y-311200D01*
X861512Y-310133D01*
X861112Y-309333D01*
X860512Y-308667D01*
X859712Y-308400D01*
G01X799712Y-283400D02*
Y-291400D01*
G01X797412Y-283400D02*
X802012D01*
G01X805812Y-288067D02*
X806512Y-287133D01*
X807112Y-286600D01*
X807912Y-286333D01*
X808612Y-286600D01*
X809112Y-287133D01*
X809512Y-287933D01*
X809612Y-288867D01*
X809512Y-289667D01*
X809112Y-290467D01*
X808512Y-291133D01*
X807812Y-291400D01*
X807012Y-291133D01*
X806312Y-290334D01*
X805912Y-289133D01*
X805812Y-287800D01*
X806012Y-286067D01*
X806312Y-285133D01*
X806812Y-284200D01*
X807512Y-283533D01*
X808212Y-283400D01*
X808912Y-283667D01*
X809412Y-284333D01*
G01X813112Y-291400D02*
Y-283400D01*
X815712Y-290067D01*
X818312Y-283400D01*
Y-291400D01*
G01X820712Y-294067D02*
X826712D01*
G01X831712Y-283400D02*
Y-291400D01*
G01X829412Y-283400D02*
X834012D01*
G01X838312Y-291400D02*
Y-286067D01*
G01Y-287133D02*
X838812Y-286600D01*
X839312Y-286200D01*
X840012Y-286067D01*
X840512Y-286200D01*
X841112Y-286600D01*
G01X849512Y-291400D02*
Y-286067D01*
G01Y-287000D02*
X849112Y-286467D01*
X848512Y-286200D01*
X847812Y-286067D01*
X847112Y-286333D01*
X846512Y-286867D01*
X846112Y-287667D01*
X845912Y-288733D01*
X846112Y-289800D01*
X846512Y-290600D01*
X847112Y-291133D01*
X847812Y-291400D01*
X848512Y-291267D01*
X849112Y-290867D01*
X849512Y-290334D01*
G01X853612Y-293800D02*
X854212Y-294067D01*
X855012Y-293800D01*
X855512Y-293267D01*
X855912Y-292600D01*
X856512Y-290467D01*
X857812Y-286067D01*
G01X854612D02*
X856512Y-290467D01*
G01X860712Y-294067D02*
X866712D01*
G01X872512Y-287133D02*
X872912Y-286733D01*
X873212Y-286067D01*
X873412Y-285133D01*
X873212Y-284333D01*
X872812Y-283800D01*
X872112Y-283400D01*
X869412D01*
Y-291400D01*
X872712D01*
X873412Y-290867D01*
X873812Y-290067D01*
X874012Y-289133D01*
X873812Y-288200D01*
X873212Y-287400D01*
X872512Y-287133D01*
X869412D01*
G01X877712Y-291400D02*
Y-283400D01*
X880112D01*
X880912Y-283800D01*
X881512Y-284733D01*
X881712Y-285800D01*
X881512Y-286867D01*
X881012Y-287667D01*
X880112Y-288067D01*
X877712D01*
G01X896912Y-334067D02*
X896312Y-333667D01*
X895612Y-333400D01*
X894812D01*
X893912Y-333800D01*
X893212Y-334467D01*
X892712Y-335267D01*
X892312Y-336600D01*
X892212Y-337800D01*
X892412Y-339000D01*
X892712Y-339800D01*
X893312Y-340600D01*
X894012Y-341133D01*
X894712Y-341400D01*
X895412D01*
X896112Y-341133D01*
X896712Y-340733D01*
X897212Y-340200D01*
G01X922212Y-341400D02*
Y-333400D01*
X921012Y-335000D01*
G01Y-341400D02*
X923412D01*
G01X928312Y-338067D02*
X929012Y-337133D01*
X929612Y-336600D01*
X930412Y-336333D01*
X931112Y-336600D01*
X931612Y-337133D01*
X932012Y-337933D01*
X932112Y-338867D01*
X932012Y-339667D01*
X931612Y-340467D01*
X931012Y-341133D01*
X930312Y-341400D01*
X929512Y-341133D01*
X928812Y-340334D01*
X928412Y-339133D01*
X928312Y-337800D01*
X928512Y-336067D01*
X928812Y-335133D01*
X929312Y-334200D01*
X930012Y-333533D01*
X930712Y-333400D01*
X931412Y-333667D01*
X931912Y-334333D01*
G01X1352481Y18898D02*
Y17461D01*
X1353000Y16942D01*
X1355037D01*
X1355637Y17542D01*
Y60400D01*
X1344500Y71537D01*
Y95600D01*
X1332679Y107421D01*
Y118900D01*
X1336166Y122387D01*
X1340252D01*
X1340721Y121918D01*
X1341258Y121650D01*
X1342063Y121917D01*
X1343938Y125666D01*
G01X1352481Y13386D02*
Y14823D01*
X1353000Y15342D01*
X1355700D01*
X1357237Y16879D01*
Y61063D01*
X1346100Y72200D01*
Y96263D01*
X1334279Y108084D01*
Y118237D01*
X1336829Y120787D01*
X1339589D01*
X1339773Y120602D01*
X1340005Y120486D01*
X1340542Y120218D01*
X1340811Y119413D01*
X1338938Y115666D01*
G01X1368229Y35433D02*
Y34027D01*
X1368779Y33477D01*
X1370785D01*
X1371779Y34471D01*
Y78137D01*
X1365879Y84037D01*
Y109037D01*
X1363779Y111137D01*
Y118963D01*
X1368029Y123213D01*
Y131387D01*
X1362116Y137300D01*
X1357479D01*
X1353129Y141650D01*
X1348938D01*
G01X1368229Y29922D02*
Y31327D01*
X1368779Y31877D01*
X1371448D01*
X1373379Y33808D01*
Y78800D01*
X1367479Y84700D01*
Y109700D01*
X1365379Y111800D01*
Y118300D01*
X1369629Y122550D01*
Y132050D01*
X1363979Y137700D01*
Y151609D01*
X1363938Y151650D01*
G01X1376103Y8268D02*
X1378059Y10224D01*
X1382766D01*
X1386779Y14237D01*
Y79900D01*
X1379279Y87400D01*
Y140418D01*
X1372869Y146828D01*
X1372332Y147096D01*
X1372063Y147901D01*
X1373938Y151650D01*
G01X1376103Y13780D02*
X1378059Y11824D01*
X1382103D01*
X1385179Y14900D01*
Y79237D01*
X1377679Y86737D01*
Y102971D01*
X1377000Y103649D01*
Y105449D01*
X1377679Y106127D01*
Y107927D01*
X1377000Y108605D01*
Y110405D01*
X1377679Y111083D01*
Y112883D01*
X1377000Y113561D01*
Y115361D01*
X1377679Y116039D01*
Y139755D01*
X1371921Y145512D01*
X1371616Y145664D01*
X1370811Y145397D01*
X1368938Y141650D01*
G01X1524478Y92100D02*
X1526178Y93800D01*
X1527151D01*
G02X1527433Y93683I0J-398D01*
G01X1527662Y93454D01*
G02X1527779Y93172I-281J-282D01*
G01Y90728D01*
G02X1527662Y90446I-398J0D01*
G01X1524030Y86814D01*
X1523094D01*
X1521821Y85541D01*
Y84605D01*
X1520548Y83332D01*
X1519612D01*
X1518339Y82059D01*
Y81123D01*
X1517066Y79850D01*
X1516130D01*
X1514857Y78577D01*
Y77641D01*
X1513584Y76368D01*
X1512648D01*
X1511375Y75095D01*
Y74159D01*
X1510102Y72886D01*
X1509166D01*
X1507893Y71613D01*
Y70678D01*
X1506333Y69118D01*
G03X1505279Y66572I2545J-2545D01*
G01Y37528D01*
G03X1506334Y34982I3600J0D01*
G01X1508384Y32931D01*
G03X1510930Y31877I2545J2545D01*
G01X1517297D01*
X1519252Y29922D01*
G01X1534388Y72900D02*
X1532688Y71200D01*
X1532689D01*
G02Y70855I-2433J-172D01*
G02X1531977Y69134I-2433J-1D01*
G01X1527931Y65088D01*
Y64232D01*
X1526660Y62961D01*
X1525804D01*
X1524087Y61245D01*
G03X1523970Y60963I281J-282D01*
G01Y59649D01*
X1524679Y58941D01*
Y57141D01*
X1523970Y56433D01*
Y12823D01*
G03X1524263Y12116I999J0D01*
G03X1524969Y11824I706J707D01*
G01X1526703D01*
X1527126Y12247D01*
Y13780D01*
G01X1529388Y72900D02*
X1529389D01*
X1530845Y71444D01*
G02X1531089Y70855I-589J-589D01*
G02X1530845Y70266I-833J0D01*
G01X1522956Y62377D01*
G03X1522370Y60963I1413J-1414D01*
G01Y12823D01*
G03X1523132Y10984I2600J0D01*
G03X1524969Y10224I1837J1840D01*
G01X1526655D01*
X1527126Y9753D01*
Y8268D01*
G01X1524478Y97100D02*
X1526178Y95400D01*
X1527151D01*
G02X1528565Y94814I0J-1999D01*
G01X1528793Y94586D01*
G02X1529379Y93172I-1413J-1414D01*
G01Y90728D01*
G02X1528793Y89314I-1999J0D01*
G01X1507465Y67986D01*
G03X1506879Y66572I1413J-1414D01*
G01Y37528D01*
G03X1507465Y36114I1999J0D01*
G01X1509516Y34063D01*
G03X1510930Y33477I1414J1413D01*
G01X1517296D01*
X1519252Y35433D01*
G01X1546141Y125930D02*
X1544442Y127629D01*
Y129009D01*
G03X1543856Y130423I-1999J0D01*
G01X1543365Y130914D01*
G03X1541951Y131500I-1414J-1413D01*
G01X1536407D01*
G03X1533861Y130445I0J-3600D01*
G01X1525033Y121618D01*
G03X1523979Y119072I2545J-2545D01*
G01Y113228D01*
G03X1525034Y110682I3600J0D01*
G01X1535462Y100254D01*
G02X1535579Y99972I-281J-282D01*
G01Y89528D01*
G02X1534993Y88114I-1999J0D01*
G01X1513633Y66755D01*
G03X1512579Y64209I2545J-2545D01*
G01Y51356D01*
G03X1513440Y49275I2943J-1D01*
G03X1515523Y48413I2082J2083D01*
G01X1518566D01*
X1519252Y47727D01*
Y46457D01*
G01X1541141Y125930D02*
X1542842Y127631D01*
Y129009D01*
G03X1542725Y129291I-398J0D01*
G01X1542233Y129783D01*
G03X1541951Y129900I-282J-281D01*
G01X1536407D01*
G03X1534993Y129314I0J-1999D01*
G01X1526165Y120486D01*
G03X1525579Y119072I1413J-1414D01*
G01Y113228D01*
G03X1526165Y111814I1999J0D01*
G01X1530263Y107716D01*
X1530721D01*
X1531180Y107718D01*
X1532455Y106443D01*
Y105524D01*
X1536593Y101386D01*
G02X1537179Y99972I-1413J-1414D01*
G01Y89528D01*
G02X1536124Y86982I-3600J0D01*
G01X1535253Y86111D01*
Y85595D01*
X1535255Y85078D01*
X1533980Y83803D01*
X1532945D01*
X1531671Y82529D01*
Y82013D01*
X1531673Y81496D01*
X1530398Y80221D01*
X1529363D01*
X1521470Y72328D01*
X1521472Y71811D01*
Y71295D01*
X1520198Y70021D01*
X1519163D01*
X1517888Y68746D01*
X1517890Y68229D01*
Y67713D01*
X1516616Y66439D01*
X1515581D01*
X1514765Y65623D01*
G03X1514179Y64209I1413J-1414D01*
G01Y51356D01*
G03X1514572Y50407I1342J0D01*
G03X1515523Y50013I951J951D01*
G01X1518492D01*
X1519252Y50773D01*
Y51969D01*
G01X1600388Y115390D02*
X1598689Y113691D01*
Y112238D01*
G02X1598103Y110824I-1999J0D01*
G01X1597465Y110186D01*
G02X1596051Y109600I-1414J1413D01*
G01X1594507D01*
G03X1593093Y109014I0J-1999D01*
G01X1589165Y105086D01*
G03X1588579Y103672I1413J-1414D01*
G01Y100928D01*
G02X1587524Y98382I-3600J0D01*
G01X1583316Y94174D01*
Y93316D01*
X1582043Y92043D01*
X1581185D01*
X1579912Y90770D01*
Y89912D01*
X1578639Y88639D01*
X1577781D01*
X1561914Y72772D01*
G02X1561610Y72522I-1416J1412D01*
G01X1557357Y69684D01*
G02X1557012Y69500I-1109J1664D01*
G01X1554724Y68552D01*
G02X1553959Y68400I-765J1849D01*
G01X1552007D01*
G03X1550593Y67814I0J-1999D01*
G01X1541868Y59089D01*
X1540249Y55177D01*
X1539753Y52200D01*
Y29149D01*
G03X1539930Y28724I599J0D01*
G01X1540024Y28630D01*
G03X1540677Y28359I653J651D01*
G01X1542266D01*
X1542874Y28967D01*
Y30315D01*
G01X1595388Y115390D02*
X1597089Y113689D01*
Y112238D01*
G02X1596972Y111956I-398J0D01*
G01X1596333Y111317D01*
G02X1596051Y111200I-282J281D01*
G01X1594507D01*
G03X1591961Y110145I0J-3600D01*
G01X1588033Y106218D01*
G03X1586979Y103672I2545J-2545D01*
G01Y100928D01*
G02X1586393Y99514I-1999J0D01*
G01X1560781Y73902D01*
G02X1560720Y73853I-279J285D01*
G01X1556469Y71016D01*
G02X1556400Y70979I-222J332D01*
G01X1554112Y70031D01*
G02X1553959Y70000I-155J370D01*
G01X1552007D01*
G03X1549461Y68945I0J-3600D01*
G01X1540511Y59995D01*
X1538700Y55620D01*
X1538153Y52333D01*
Y29149D01*
G03X1538800Y27591I2199J0D01*
G01X1538892Y27499D01*
G03X1540677Y26759I1785J1783D01*
G01X1542353D01*
X1542874Y26238D01*
Y24803D01*
G01X1625488Y124730D02*
X1627189Y126431D01*
Y127362D01*
G03X1627072Y127644I-398J0D01*
G01X1626733Y127983D01*
G03X1626451Y128100I-282J-281D01*
G01X1624562D01*
G03X1623796Y127948I-1J-2000D01*
G01X1616676Y124997D01*
G03X1616320Y124805I766J-1847D01*
G01X1614197Y123367D01*
G03X1613904Y123125I1121J-1656D01*
G01X1612219Y121440D01*
G03X1611969Y121135I1414J-1414D01*
G01X1609625Y117619D01*
G03X1609441Y117275I1663J-1111D01*
G01X1609123Y116507D01*
G03X1609079Y116284I538J-222D01*
G01Y115918D01*
G02X1608927Y115152I-2000J-1D01*
G01X1603910Y103046D01*
G02X1603477Y102398I-1848J766D01*
G01X1602010Y100931D01*
Y100033D01*
X1600737Y98760D01*
X1599839D01*
X1598566Y97487D01*
Y96589D01*
X1597293Y95316D01*
X1596395D01*
X1595122Y94043D01*
Y93145D01*
X1593849Y91872D01*
X1592951D01*
X1591678Y90599D01*
Y89701D01*
X1590405Y88428D01*
X1589507D01*
X1588234Y87155D01*
Y86257D01*
X1586961Y84984D01*
X1586063D01*
X1584790Y83711D01*
Y82813D01*
X1583517Y81540D01*
X1582619D01*
X1581557Y80478D01*
X1571534Y72197D01*
X1563257Y64941D01*
X1553261Y60382D01*
X1547567Y54688D01*
X1547427Y54349D01*
Y51445D01*
G03X1547847Y50432I1432J0D01*
G03X1548859Y50013I1012J1013D01*
G01X1549992D01*
X1550748Y50769D01*
Y51969D01*
G01X1630488Y124730D02*
X1628789Y126429D01*
Y127362D01*
G03X1628203Y128776I-1999J0D01*
G01X1627865Y129114D01*
G03X1626451Y129700I-1414J-1413D01*
G01X1624563D01*
G03X1623183Y129427I-5J-3601D01*
G01X1616063Y126475D01*
G03X1615422Y126130I1377J-3326D01*
G01X1613300Y124692D01*
G03X1612772Y124257I2015J-2984D01*
G01X1611087Y122572D01*
G03X1610637Y122023I2546J-2546D01*
G01X1608294Y118507D01*
G03X1607963Y117888I2994J-1999D01*
G01X1607644Y117118D01*
G03X1607479Y116284I2017J-832D01*
G01Y115917D01*
G02X1607448Y115764I-400J1D01*
G01X1602432Y103659D01*
G02X1602345Y103529I-370J153D01*
G01X1580499Y81683D01*
G02X1580457Y81645I-423J425D01*
G01X1570504Y73422D01*
G03X1570491Y73411I382J-464D01*
G01X1570478Y73400D01*
X1570479D01*
X1562379Y66300D01*
X1552334Y61718D01*
X1546210Y55594D01*
X1545827Y54667D01*
Y51445D01*
G03X1546716Y49300I3032J0D01*
G03X1548859Y48413I2143J2145D01*
G01X1549966D01*
X1550748Y47631D01*
Y46457D01*
G01X1565039Y122030D02*
X1563340Y123729D01*
Y125011D01*
G03X1562754Y126425I-1999J0D01*
G01X1562065Y127114D01*
G03X1560651Y127700I-1414J-1413D01*
G01X1559407D01*
G03X1557992Y127114I-1J-2000D01*
G01X1555715Y124837D01*
X1553402Y122521D01*
G03X1552779Y121071I1376J-1450D01*
G01Y102928D01*
G03X1553833Y100382I3599J-1D01*
G01X1554162Y100054D01*
G02X1554279Y99772I-281J-282D01*
G01Y92228D01*
G02X1554162Y91946I-398J0D01*
G01X1541634Y79418D01*
G03X1540579Y76872I2545J-2546D01*
G01Y69728D01*
G02X1540462Y69446I-398J0D01*
G01X1531134Y60118D01*
G03X1530079Y57572I2545J-2546D01*
G01Y51528D01*
G03X1530990Y49325I3114J-2D01*
G01X1530992Y49323D01*
G03X1533192Y48413I2200J2204D01*
G01X1534266D01*
X1535000Y47679D01*
Y46457D01*
G01X1560039Y122030D02*
X1561740Y123731D01*
Y125011D01*
G03X1561623Y125293I-398J0D01*
G01X1560933Y125983D01*
G03X1560651Y126100I-282J-281D01*
G01X1559406D01*
G03X1559124Y125983I1J-400D01*
G01X1558204Y125062D01*
X1556847Y123706D01*
X1554519Y121375D01*
X1554503Y121360D01*
G03X1554379Y121071I275J-289D01*
G01Y117514D01*
X1555079Y116814D01*
Y115214D01*
X1554379Y114514D01*
Y112714D01*
X1555079Y112014D01*
Y110414D01*
X1554379Y109714D01*
Y107408D01*
X1554979Y106808D01*
Y105008D01*
X1554379Y104408D01*
Y102928D01*
G03X1554965Y101514I1999J0D01*
G01X1555293Y101186D01*
G02X1555879Y99772I-1413J-1414D01*
G01Y92228D01*
G02X1555293Y90814I-1999J0D01*
G01X1554521Y90042D01*
Y89142D01*
X1553248Y87869D01*
X1552348D01*
X1551075Y86596D01*
Y85696D01*
X1549802Y84423D01*
X1548902D01*
X1547629Y83150D01*
Y82250D01*
X1546356Y80977D01*
X1545456D01*
X1542765Y78286D01*
G03X1542179Y76872I1413J-1414D01*
G01Y69728D01*
G02X1541593Y68314I-1999J0D01*
G01X1532265Y58986D01*
G03X1531679Y57572I1413J-1414D01*
G01Y51527D01*
G03X1532122Y50456I1514J-1D01*
G01X1532123Y50455D01*
G03X1533192Y50013I1069J1072D01*
G01X1534392D01*
X1535000Y50621D01*
Y51969D01*
G01X1648278Y97130D02*
X1649978Y95430D01*
X1651233D01*
G02X1653246Y94597I1J-2846D01*
G02X1654079Y92584I-2013J-2012D01*
G01Y90320D01*
G02X1653927Y89554I-2000J-1D01*
G01X1651685Y84145D01*
G02X1651501Y83799I-1849J762D01*
G01X1651499Y83796D01*
Y83795D01*
X1630368Y52178D01*
X1630258Y52017D01*
X1626192Y47951D01*
Y47013D01*
X1624920Y45741D01*
X1623982D01*
X1622710Y44469D01*
Y43531D01*
X1621438Y42259D01*
X1620500D01*
X1619228Y40987D01*
Y40049D01*
X1617956Y38777D01*
X1617018D01*
X1615746Y37505D01*
Y36567D01*
X1614474Y35295D01*
X1613536D01*
X1612264Y34023D01*
Y33085D01*
X1610992Y31813D01*
X1610054D01*
X1608782Y30541D01*
Y29603D01*
X1607510Y28331D01*
X1606572D01*
X1601358Y23117D01*
G02X1600937Y22771I-1976J1975D01*
G02X1600703Y22630I-1554J2314D01*
G02X1600456Y22512I-1324J2453D01*
G01X1571524Y10475D01*
G02X1570141Y10200I-1380J3325D01*
G01X1560554D01*
X1558622Y8268D01*
G01X1550748Y29922D02*
Y31072D01*
X1551553Y31877D01*
X1553139D01*
G03X1554812Y32569I1J2366D01*
G03X1555504Y34242I-1674J1672D01*
G01Y52297D01*
G02X1556090Y53711I1999J0D01*
G01X1556793Y54414D01*
G02X1558207Y55000I1414J-1413D01*
G01X1563390D01*
X1563990Y54400D01*
X1565790D01*
X1566390Y55000D01*
X1568190D01*
X1568790Y54400D01*
X1570590D01*
X1571190Y55000D01*
X1572990D01*
X1573590Y54400D01*
X1575390D01*
X1575990Y55000D01*
X1577790D01*
X1578390Y54400D01*
X1580190D01*
X1580790Y55000D01*
X1582590D01*
X1583190Y54400D01*
X1584990D01*
X1585590Y55000D01*
X1587151D01*
G03X1589697Y56055I0J3600D01*
G01X1619805Y86162D01*
G03X1620859Y88708I-2545J2545D01*
G01Y91131D01*
X1622558Y92830D01*
G01X1648278Y92130D02*
X1649978Y93830D01*
X1651233D01*
G02X1652114Y93465I0J-1246D01*
G02X1652479Y92585I-881J-881D01*
G01Y90319D01*
X1652478D01*
G02X1652448Y90166I-399J-1D01*
G01X1650206Y84756D01*
X1650205Y84755D01*
G02X1650169Y84686I-370J149D01*
G01X1629040Y53072D01*
X1629019Y53041D01*
X1600226Y24248D01*
G02X1600045Y24100I-842J845D01*
G02X1599944Y24039I-663J984D01*
G02X1599841Y23990I-561J1046D01*
G01X1570909Y11953D01*
G02X1570141Y11800I-767J1847D01*
G01X1560602D01*
X1558622Y13780D01*
G01X1617558Y92830D02*
X1619259Y91129D01*
Y88708D01*
G02X1618673Y87294I-1999J0D01*
G01X1588565Y57186D01*
G02X1587151Y56600I-1414J1413D01*
G01X1558207D01*
G03X1555661Y55546I-1J-3599D01*
G01X1554959Y54843D01*
G03X1553904Y52297I2545J-2546D01*
G01Y34241D01*
G02X1553680Y33701I-765J1D01*
G02X1553139Y33477I-541J541D01*
G01X1551653D01*
X1550748Y34382D01*
Y35433D01*
G01X1627007Y72900D02*
X1628708Y71199D01*
Y69357D01*
G02X1628122Y67943I-1999J0D01*
G01X1605660Y45481D01*
G02X1604246Y44895I-1414J1413D01*
G01X1560578D01*
X1558622Y46851D01*
G01X1632007Y72900D02*
X1630308Y71201D01*
Y69357D01*
G02X1629254Y66811I-3599J-1D01*
G01X1606792Y44350D01*
G02X1604246Y43295I-2546J2545D01*
G01X1588078D01*
X1587384Y42600D01*
X1585584D01*
X1584890Y43295D01*
X1583090D01*
X1582396Y42600D01*
X1580596D01*
X1579902Y43295D01*
X1578102D01*
X1577408Y42600D01*
X1575608D01*
X1574914Y43295D01*
X1560578D01*
X1558622Y41339D01*
G54D16*
X343780Y11810D03*
Y19684D03*
Y27558D03*
X335906Y11810D03*
Y19684D03*
Y27558D03*
X343780Y43306D03*
Y51180D03*
X335906Y43306D03*
Y51180D03*
X343780Y59054D03*
X335906D03*
X1205984Y11810D03*
Y19684D03*
Y27558D03*
Y43306D03*
Y51180D03*
Y59054D03*
X1213858Y11810D03*
Y19684D03*
Y27558D03*
Y43306D03*
Y51180D03*
Y59054D03*
G54D26*
G01X99100Y127470D02*
X110140Y116430D01*
X325482D01*
X342965Y133913D01*
X431153D01*
X443166Y121900D01*
X458300D01*
X468600Y132200D01*
X474200D01*
X479300Y127100D01*
Y121300D01*
X475300Y117300D01*
Y111400D01*
X490900Y95800D01*
Y75800D01*
X488800Y73700D01*
G01X107390Y125110D02*
X114150Y118350D01*
X324686D01*
X342169Y135833D01*
X431949D01*
X443782Y124000D01*
X457500D01*
X467700Y134200D01*
X480200D01*
X487600Y126800D01*
Y123200D01*
X483050Y118650D01*
Y107180D01*
X493000Y97230D01*
Y82730D01*
X493300Y82430D01*
Y44363D01*
X490276Y41339D01*
G01X102590Y115680D02*
X106100Y112170D01*
X326654D01*
X344557Y130073D01*
X429560D01*
X472500Y87133D01*
Y58500D01*
X477400Y53600D01*
Y45947D01*
X482402Y40945D01*
G01X115400Y120270D02*
X323172D01*
X342502Y139600D01*
X430898D01*
X436198Y134300D01*
X442100D01*
X447000Y139200D01*
X463100D01*
X466000Y136300D01*
X481000D01*
X489600Y127700D01*
Y122300D01*
X485150Y117850D01*
Y108050D01*
X495100Y98100D01*
Y83600D01*
X495400Y83300D01*
Y49207D01*
X498150Y46457D01*
G01X119800Y124390D02*
X321860D01*
X343470Y146000D01*
X459500D01*
X471930Y158430D01*
X514340D01*
X526290Y146480D01*
X612720D01*
X616100Y143100D01*
X627000D01*
X630380Y146480D01*
X795690D01*
X808390Y133780D01*
X1248756D01*
X1264296Y118240D01*
X1310360D01*
X1328900Y99700D01*
Y95900D01*
X1337600Y87200D01*
Y63479D01*
X1347479Y53600D01*
Y45947D01*
X1352481Y40945D01*
G01X108900Y137300D02*
X117800Y128400D01*
X320438D01*
X342538Y150500D01*
X436151D01*
X448789Y163138D01*
X515862D01*
X528680Y150320D01*
X798162D01*
X810862Y137620D01*
X1250660D01*
X1266200Y122080D01*
X1328185D01*
X1336631Y130526D01*
X1345952D01*
X1349379Y127099D01*
Y121300D01*
X1345379Y117300D01*
Y111400D01*
X1355139Y101640D01*
Y81761D01*
X1361500Y75400D01*
Y72300D01*
X1358200Y69000D01*
G01X114300Y134900D02*
X118800Y130400D01*
X319722D01*
X341822Y152500D01*
X435434D01*
X447992Y165058D01*
X517342D01*
X530160Y152240D01*
X799071D01*
X811771Y139540D01*
X1251456D01*
X1266996Y124000D01*
X1327389D01*
X1335889Y132500D01*
X1351979D01*
X1357479Y127000D01*
Y123900D01*
X1353129Y119550D01*
Y110871D01*
X1357100Y106900D01*
Y83000D01*
X1363500Y76600D01*
Y44484D01*
X1360355Y41339D01*
G01X119700Y132400D02*
X319006D01*
X341106Y154500D01*
X434718D01*
X447196Y166978D01*
X518300D01*
X531118Y154160D01*
X799980D01*
X812680Y141460D01*
X1252340D01*
X1267880Y125920D01*
X1306220D01*
X1319900Y139600D01*
X1328200D01*
X1333200Y134600D01*
X1352979D01*
X1360279Y127300D01*
Y122900D01*
X1355229Y117850D01*
Y112071D01*
X1361000Y106300D01*
Y81900D01*
X1365479Y77421D01*
Y49207D01*
X1368229Y46457D01*
G01X111500Y129900D02*
X118930Y122470D01*
X322656D01*
X341786Y141600D01*
X433700D01*
X436100Y144000D01*
X461000D01*
X473510Y156510D01*
X513290D01*
X525240Y144560D01*
X611840D01*
X615300Y141100D01*
X627740D01*
X631200Y144560D01*
X794640D01*
X807340Y131860D01*
X1247960D01*
X1263500Y116320D01*
X1309480D01*
X1326200Y99600D01*
Y95600D01*
X1335600Y86200D01*
Y61779D01*
X1341879Y55500D01*
Y44067D01*
X1344607Y41339D01*
G01X128600Y114510D02*
X326278D01*
X343761Y131993D01*
X430357D01*
X474700Y87650D01*
Y59500D01*
X479600Y54600D01*
Y49259D01*
X482402Y46457D01*
G01X132500Y110100D02*
X327300D01*
X345300Y128100D01*
X428816D01*
X468900Y88016D01*
Y58400D01*
X471800Y55500D01*
Y44067D01*
X474528Y41339D01*
G01X125000Y126400D02*
X321154D01*
X342954Y148200D01*
X436568D01*
X449586Y161218D01*
X514664D01*
X527482Y148400D01*
X613600D01*
X616900Y145100D01*
X626100D01*
X629400Y148400D01*
X796882D01*
X809582Y135700D01*
X1249553D01*
X1265093Y120160D01*
X1311240D01*
X1331100Y100300D01*
Y96500D01*
X1339600Y88000D01*
Y64679D01*
X1349679Y54600D01*
Y49259D01*
X1352481Y46457D01*
G01X357800Y114657D02*
X369975D01*
X399032Y85600D01*
X412300D01*
G01X357600Y108561D02*
X373355D01*
X399616Y82300D01*
X406181D01*
G01X356861Y102961D02*
X376239D01*
X399882Y79318D01*
G01X412480Y80900D02*
Y81880D01*
X416700Y86100D01*
X431152D01*
X432752Y84500D01*
X444300D01*
X452100Y92300D01*
X453900D01*
G01X403032Y89532D02*
X408720Y95220D01*
X442820D01*
X449800Y102200D01*
X452000D01*
G01X415630Y80700D02*
X417730Y82800D01*
X430800D01*
X432500Y81100D01*
X445200D01*
X450900Y86800D01*
X453300D01*
G01X409331Y88600D02*
X414031Y93300D01*
X443800D01*
X447500Y97000D01*
X452100D01*
G01X451100Y81400D02*
X448200Y78500D01*
X430800D01*
X429340Y79960D01*
X422489D01*
X421929Y79400D01*
Y78400D01*
G01X453900Y92300D02*
X461300Y84900D01*
Y47400D01*
X465000Y43700D01*
X468400D01*
X469309Y42791D01*
X469314D01*
X473605Y38500D01*
X479335D01*
X482402Y35433D01*
G01X453300Y86800D02*
X457900Y82200D01*
Y45100D01*
X464800Y38200D01*
X468200D01*
X473400Y33000D01*
X479324D01*
X482402Y29922D01*
G01X452000Y102200D02*
X455000Y99200D01*
Y98758D01*
X466200Y87558D01*
G01X452100Y97000D02*
X453400D01*
X466100Y84300D01*
Y83258D01*
G01X564922Y81900D02*
X560122Y86700D01*
X548734D01*
X536134Y99300D01*
X525700D01*
G01X561772Y80800D02*
X559312Y83260D01*
X548440D01*
X536500Y95200D01*
X520600D01*
X519400Y96400D01*
G01X558623Y79200D02*
X555600D01*
X554300Y80500D01*
X547400D01*
X535300Y92600D01*
X528200D01*
X526600Y91000D01*
X520439D01*
G01X516500Y87442D02*
X519242Y84700D01*
X535900D01*
X543400Y77200D01*
X551024D01*
X552324Y78500D01*
G01X615500Y105157D02*
X603057D01*
X592700Y94800D01*
X579700D01*
X575000Y90100D01*
X553800D01*
X553100Y89400D01*
X549174D01*
G01X614900Y90157D02*
X604757D01*
X597100Y82500D01*
X574021D01*
X571221Y79700D01*
G01X615600Y95139D02*
X606910D01*
X596271Y84500D01*
X571072D01*
X568072Y81500D01*
G01X615500Y100157D02*
X601057D01*
X593600Y92700D01*
X581000D01*
X576000Y87700D01*
X563800D01*
G01X1226900Y119561D02*
X1237750D01*
X1270911Y86400D01*
X1277100D01*
X1281900Y81600D01*
X1288800D01*
X1290208Y80192D01*
X1292008D01*
G01X1226900Y114043D02*
X1240552D01*
X1270895Y83700D01*
X1276600D01*
X1281900Y78400D01*
X1288859D01*
G01X1227000Y108361D02*
X1243518D01*
X1272879Y79000D01*
X1276260D01*
G01X1227100Y102861D02*
X1245502D01*
X1267379Y80984D01*
Y80982D01*
X1269961Y78400D01*
G01X1273111Y89100D02*
X1278594D01*
X1284394Y94900D01*
X1314700D01*
X1319039Y99239D01*
X1323000D01*
G01X1279410Y87200D02*
X1285010Y92800D01*
X1321400D01*
G01X1285709Y84300D02*
X1301200D01*
X1303500Y82000D01*
X1316800D01*
X1317400Y82600D01*
X1321500D01*
G01X1282559Y85700D02*
X1283859Y87000D01*
X1302600D01*
X1305000Y84600D01*
X1313961D01*
X1317161Y87800D01*
X1322500D01*
G01X1321500Y82600D02*
Y50179D01*
X1333579Y38100D01*
X1338079D01*
X1339479Y36700D01*
Y35300D01*
X1341779Y33000D01*
X1349403D01*
X1352481Y29922D01*
G01X1322500Y87800D02*
X1325000Y85300D01*
Y53500D01*
X1334800Y43700D01*
X1338484D01*
X1343684Y38500D01*
X1349414D01*
X1352481Y35433D01*
G01X1323000Y99239D02*
Y95700D01*
X1333500Y85200D01*
Y83000D01*
X1333400Y82900D01*
G01X1321400Y92800D02*
X1329500Y84700D01*
Y81400D01*
G01X1422403Y78400D02*
X1419500D01*
X1417640Y80260D01*
X1416040D01*
X1411900Y84400D01*
X1390242D01*
X1387400Y87242D01*
G01X1435001Y81700D02*
X1430821Y85880D01*
X1428020D01*
X1425600Y88300D01*
X1418200D01*
X1408600Y97900D01*
X1396800D01*
X1395200Y99500D01*
G01X1389900Y97600D02*
X1392200Y95300D01*
X1407600D01*
X1417300Y85600D01*
X1424600D01*
X1427100Y83100D01*
X1428951D01*
X1431851Y80200D01*
G01X1428702Y79002D02*
X1426098D01*
X1422200Y82900D01*
X1416433D01*
X1406933Y92400D01*
X1391000D01*
G01X1484900Y103257D02*
X1477657D01*
X1468700Y94300D01*
X1450200D01*
X1444000Y88100D01*
X1434200D01*
G01X1484800Y109357D02*
X1462057D01*
X1443100Y90400D01*
X1431300D01*
X1429400Y88500D01*
G01X1484700Y93057D02*
X1476357D01*
X1465400Y82100D01*
X1444300D01*
X1441300Y79100D01*
G01X1485000Y98057D02*
X1476057D01*
X1462600Y84600D01*
X1441651D01*
X1438151Y81100D01*
G54D17*
X383642Y158642D03*
X405964Y178327D03*
X439744D03*
X532934Y158642D03*
X555256Y178327D03*
X589036D03*
X1253721Y158642D03*
X1276043Y178327D03*
X1309823Y138957D03*
Y178327D03*
X1403012Y119272D03*
Y158642D03*
X1415492Y99587D03*
X1436752D03*
X1425334Y178327D03*
X1459114Y138957D03*
Y178327D03*
G54D18*
X468859Y115666D03*
X473859Y125666D03*
X478859Y141650D03*
X498859D03*
X493859Y151650D03*
X503859D03*
X1338938Y115666D03*
X1343938Y125666D03*
X1348938Y141650D03*
X1363938Y151650D03*
X1368938Y141650D03*
X1373938Y151650D03*
G54D19*
X452875Y194642D03*
X519843D03*
X1322954D03*
X1325946Y153658D03*
X1389922Y115666D03*
X1386930Y140666D03*
X1389922Y194642D03*
M02*
